G04 ================== begin FILE IDENTIFICATION RECORD ==================*
G04 Layout Name:  15968-1a.brd*
G04 Film Name:    DP_REF_L1*
G04 File Format:  Gerber RS274X*
G04 File Origin:  Cadence Allegro 16.5-S058*
G04 Origin Date:  Fri Oct 14 10:23:46 2016*
G04 *
G04 Layer:  BOARD GEOMETRY/DP_REF_L1_TBL*
G04 Layer:  BOARD GEOMETRY/DP_REF_L1_TOP*
G04 Layer:  BOARD GEOMETRY/PANEL_OUTLINE*
G04 *
G04 Offset:    (0.00 0.00)*
G04 Mirror:    No*
G04 Mode:      Positive*
G04 Rotation:  0*
G04 FullContactRelief:  No*
G04 UndefLineWidth:     6.00*
G04 ================== end FILE IDENTIFICATION RECORD ====================*
%FSLAX35Y35*MOIN*%
%IR0*IPPOS*OFA0.00000B0.00000*MIA0B0*SFA1.00000B1.00000*%
%ADD10C,.02*%
%ADD11C,.005*%
%ADD12C,.006*%
%ADD13C,.0045*%
G75*
%LPD*%
G75*
G54D10*
G01X687653Y496146D02*
X1212653D01*
G01X687653Y461496D02*
X1212653D01*
G01X687653Y426846D02*
X1212653D01*
G01X687653Y530796D02*
Y426846D01*
G01Y530796D02*
X1212653D01*
G01X862653D02*
Y426846D01*
G01X1107653Y530796D02*
Y426846D01*
G01X1212653Y530796D02*
Y426846D01*
G54D11*
G01X-21653Y-58346D02*
G03X-6653Y-73346I15000J0D01*
G01X65080D02*
X-6653D01*
G01X9506Y0D02*
X69017D01*
G01X6722Y1153D02*
G03X9506Y0I2784J2784D01*
G01X1154Y6721D02*
X6722Y1153D01*
G01X1Y9505D02*
G03X1154Y6721I3937J0D01*
G01X1Y238051D02*
Y9505D01*
G01Y238051D02*
Y9505D01*
G01X-21653Y238051D02*
Y9505D01*
G01X1D02*
G03X1154Y6721I3937J0D01*
G01X-7873Y9505D02*
G03X-4414Y1153I11811J-1D01*
G01X1154Y6721D02*
X6722Y1153D01*
G01X-4414D02*
X1154Y-4415D01*
G01X6722Y1153D02*
G03X9506Y0I2784J2784D01*
G01X1154Y-4415D02*
G03X9506Y-7874I8351J8352D01*
G01Y0D02*
X69017D01*
G01X9506Y-7874D02*
X14917D01*
G01X-21653Y9505D02*
Y-58346D01*
G01X14917Y-7874D02*
G03Y0I0J3937D01*
G01X-7873Y50852D02*
Y9505D01*
G01Y81561D02*
G03X1I3937J-1D01*
G01Y50852D02*
G03X-7873I-3937J0D01*
G01Y186482D02*
Y81561D01*
G01X13443Y249862D02*
X611812D01*
G01X10659Y251015D02*
G03X13443Y249862I2784J2784D01*
G01X1154Y260520D02*
X10659Y251015D01*
G01X3938Y241988D02*
G03X1Y238051I0J-3937D01*
G01X602307Y241988D02*
X3938D01*
G01X602307D02*
X3938D01*
G01D02*
G03X1Y238051I0J-3937D01*
G01X-7873D02*
Y217191D01*
G01X1154Y260520D02*
X10659Y251015D01*
G01D02*
G03X13443Y249862I2784J2784D01*
G01D02*
X611812D01*
G01X-21653Y238051D02*
Y534327D01*
G01X-7873Y238051D02*
Y263304D01*
G01Y217191D02*
G03X1I3937J-1D01*
G01Y186482D02*
G03X-7873I-3937J0D01*
G01X1Y263304D02*
G03X1154Y260520I3937J0D01*
G01X1Y328602D02*
Y263304D01*
G01X3938Y332539D02*
G03X1Y328602I0J-3937D01*
G01X53151Y332539D02*
X3938D01*
G01X53151D02*
X3938D01*
G01D02*
G03X1Y328602I0J-3937D01*
G01X3938Y340413D02*
G03X-7873Y328602I0J-11811D01*
G01X1D02*
Y263304D01*
G01X-7873Y328602D02*
Y263304D01*
G01X1D02*
G03X1154Y260520I3937J0D01*
G01X10965Y332539D02*
G03Y340413I0J3937D01*
G01D02*
X3938D01*
G01X-6653Y565196D02*
G03X-21653Y550196I0J-15000D01*
G01X67796Y565196D02*
X-6653D01*
G01X-21653Y542201D02*
Y550196D01*
G01Y534327D02*
G03Y542201I0J3937D01*
G01X74922Y-73346D02*
X175828D01*
G01X72954Y-71378D02*
X74922Y-73346D01*
G01X72954Y-3937D02*
Y-71378D01*
G01X65080Y-7874D02*
Y-71772D01*
G01D02*
Y-73346D01*
G01X72954Y-3937D02*
G03X69017Y0I-3937J0D01*
G01X72954Y-3937D02*
G03X69017Y0I-3937J0D01*
G01X45626D02*
G03Y-7874I0J-3937D01*
G01D02*
X65080D01*
G01X51397Y241988D02*
G03Y249862I0J3937D01*
G01X93906D02*
G03Y241988I0J-3937D01*
G01X53151Y332539D02*
G03X57088Y336476I0J3937D01*
G01Y482345D02*
Y336476D01*
G01Y482345D02*
Y336476D01*
G01X53151Y332539D02*
G03X57088Y336476I0J3937D01*
G01X41674Y340413D02*
G03Y332539I0J-3937D01*
G01X49214Y340413D02*
X41674D01*
G01X49214Y442487D02*
Y340413D01*
G01X67796Y565196D02*
Y499724D01*
G01X75670Y563228D02*
Y495787D01*
G01X58241Y485129D02*
G03X57088Y482345I2784J-2784D01*
G01X63808Y490697D02*
X58241Y485129D01*
G01X66592Y491850D02*
G03X63808Y490697I0J-3937D01*
G01X71733Y491850D02*
X66592D01*
G01X71733D02*
G03X75670Y495787I0J3937D01*
G01X67796Y499724D02*
X66592D01*
G01Y491850D02*
G03X63808Y490697I0J-3937D01*
G01X66592Y499724D02*
G03X58240Y496265I-1J-11811D01*
G01X63808Y490697D02*
X58241Y485129D01*
G01X58240Y496264D02*
X52673Y490696D01*
G01X58241Y485129D02*
G03X57088Y482345I2784J-2784D01*
G01X52673Y490697D02*
G03X49214Y482343I8352J-8351D01*
G01Y482345D02*
Y473195D01*
G01X57088Y442487D02*
G03X49214I-3937J-1D01*
G01Y473195D02*
G03X57088I3937J0D01*
G01X77639Y565196D02*
X75670Y563228D01*
G01X173111Y565196D02*
X77639D01*
G01X177796Y-71378D02*
Y-52874D01*
G01X175828Y-73346D02*
X177796Y-71378D01*
G01X156723Y-56383D02*
Y-57811D01*
G01X157923Y-56621D02*
Y-57536D01*
G01X158163Y-52895D02*
X156723Y-56383D01*
G01X181888Y1424D02*
X157923Y-56621D01*
G01X159834Y-48847D02*
X159262Y-50233D01*
G01X181888Y1424D02*
X157923Y-56621D01*
G01X180728Y1761D02*
X160933Y-46185D01*
G01X181888Y1424D02*
X157923Y-56621D01*
G01X192959Y71142D02*
X180728Y1761D01*
G01X194141Y70934D02*
X181888Y1424D01*
G01X166172Y-56104D02*
Y-57445D01*
G01X167372Y-56327D02*
Y-57323D01*
G01X187642Y-364D02*
X166214Y-55994D01*
G01X169636Y-50449D02*
X167372Y-56327D01*
G01X171211Y-46361D02*
X170672Y-47761D01*
G01X188800Y-700D02*
X172246Y-43674D01*
G01X157923Y-56621D02*
Y-57536D01*
G01X156723Y-56383D02*
Y-57811D01*
G01X181888Y1424D02*
X157923Y-56621D01*
G01X158163Y-52895D02*
X156723Y-56383D01*
G01X159834Y-48847D02*
X159262Y-50233D01*
G01X180728Y1761D02*
X160933Y-46185D01*
G01X194141Y70934D02*
X181888Y1424D01*
G01X192959Y71142D02*
X180728Y1761D01*
G01X167372Y-56327D02*
Y-57323D01*
G01X166172Y-56104D02*
Y-57445D01*
G01X169636Y-50449D02*
X167372Y-56327D01*
G01X187642Y-364D02*
X166214Y-55994D01*
G01X171211Y-46361D02*
X170672Y-47761D01*
G01X187642Y-364D02*
X166214Y-55994D01*
G01X188800Y-700D02*
X172246Y-43674D01*
G01X187642Y-364D02*
X166214Y-55994D01*
G01X128377Y-56100D02*
Y-56834D01*
G01X129577Y-57288D02*
Y-56330D01*
G01X129785Y-52556D02*
X128377Y-56100D01*
G01X129577Y-56330D02*
X130900Y-53000D01*
G01X129896Y-52274D02*
X129785Y-52556D01*
G01X129577Y-56330D02*
X130900Y-53000D01*
G01X131046Y-51311D02*
X129896Y-52274D01*
G01X130900Y-53000D02*
X145284Y-40948D01*
G01X133253Y-49461D02*
X132281Y-49375D01*
G01X130900Y-53000D02*
X145284Y-40948D01*
G01X134403Y-48498D02*
X133253Y-49461D01*
G01X130900Y-53000D02*
X145284Y-40948D01*
G01X136611Y-46648D02*
X135639Y-46562D01*
G01X130900Y-53000D02*
X145284Y-40948D01*
G01X144471Y-40062D02*
X136611Y-46648D01*
G01X130900Y-53000D02*
X145284Y-40948D01*
G01X145626Y-38902D02*
X144471Y-40062D01*
G01X146496Y-39742D02*
X146498Y-39740D01*
G01X145284Y-40948D02*
X146484Y-39742D01*
G01X145628Y-38900D02*
X145626Y-38902D01*
G01X145284Y-40948D02*
X146484Y-39742D01*
G01X160494Y-17658D02*
X145636Y-38878D01*
G01X146498Y-39740D02*
X176490Y3092D01*
G01X175353Y3562D02*
X160494Y-17658D01*
G01X146498Y-39740D02*
X176490Y3092D01*
G01X188368Y77367D02*
X175354Y3562D01*
G01X176490Y3092D02*
X189605Y77471D01*
G01X176490Y3092D02*
X189605Y77471D01*
G01X188368Y77367D02*
X175354Y3562D01*
G01X146498Y-39740D02*
X176490Y3092D01*
G01X160494Y-17658D02*
X145636Y-38878D01*
G01X175353Y3562D02*
X160494Y-17658D01*
G01X146496Y-39742D02*
X146498Y-39740D01*
G01X145626Y-38902D02*
X144471Y-40062D01*
G01X145284Y-40948D02*
X146484Y-39742D01*
G01X145626Y-38902D02*
X144471Y-40062D01*
G01X145628Y-38900D02*
X145626Y-38902D01*
G01X130900Y-53000D02*
X145284Y-40948D01*
G01X131046Y-51311D02*
X129896Y-52274D01*
G01X133253Y-49461D02*
X132281Y-49375D01*
G01X134403Y-48498D02*
X133253Y-49461D01*
G01X136611Y-46648D02*
X135639Y-46562D01*
G01X144471Y-40062D02*
X136611Y-46648D01*
G01X129577Y-56330D02*
X130900Y-53000D01*
G01X129785Y-52556D02*
X128377Y-56100D01*
G01X129896Y-52274D02*
X129785Y-52556D01*
G01X129577Y-57288D02*
Y-56330D01*
G01X128377Y-56100D02*
Y-56834D01*
G01X187245Y-52874D02*
G03X177796I-4725J0D01*
G01X175466Y113607D02*
X188368Y77367D01*
G01X189605Y77471D02*
X176600Y114002D01*
G01X189605Y77471D02*
X176600Y114002D01*
G01X175466Y113607D02*
X188368Y77367D01*
G01X185315Y128108D02*
X194221Y78298D01*
G01X186500Y128300D02*
X195440Y78299D01*
G01X185312Y128128D02*
X185315Y128108D01*
G01X185940Y132150D02*
X186500Y128300D01*
G01X184737Y132083D02*
X185312Y128128D01*
G01X185940Y132150D02*
X186500Y128300D01*
G01X184052Y133347D02*
G02X184740Y132190I-559J-1116D01*
G01X184588Y134421D02*
G02X185940Y132150I-1095J-2190D01*
G01X183604Y133570D02*
X184052Y133347D01*
G01X184147Y134641D02*
X184588Y134421D01*
G01X184141Y134643D02*
X184142D01*
G01X183603Y133570D02*
X183604D01*
G01X184147Y134641D02*
X184588Y134421D01*
G01X186500Y128300D02*
X195440Y78299D01*
G01X185315Y128108D02*
X194221Y78298D01*
G01X185940Y132150D02*
X186500Y128300D01*
G01X185312Y128128D02*
X185315Y128108D01*
G01X184737Y132083D02*
X185312Y128128D01*
G01X184588Y134421D02*
G02X185940Y132150I-1095J-2190D01*
G01X184052Y133347D02*
G02X184740Y132190I-559J-1116D01*
G01X184147Y134641D02*
X184588Y134421D01*
G01X183604Y133570D02*
X184052Y133347D01*
G01X183603Y133570D02*
X183604D01*
G01X184141Y134643D02*
X184142D01*
G01X183604Y133570D02*
X184052Y133347D01*
G01X168957Y125190D02*
X175453Y113613D01*
G01X176600Y114023D02*
X170084Y125634D01*
G01X168634Y126516D02*
X168957Y125190D01*
G01X170084Y125634D02*
X169800Y126800D01*
G01X168300Y129300D02*
G03X168634Y126516I11767J0D01*
G01X169800Y126800D02*
G02X169500Y129300I10267J2500D01*
G01X168300Y130889D02*
Y129300D01*
G01X169500D02*
Y130890D01*
G01X170278Y135513D02*
G03X168300Y130889I4412J-4622D01*
G01X169500Y130890D02*
G02X171020Y134560I5190J0D01*
G01X173430Y139573D02*
G02X170278Y135513I-6806J2030D01*
G01X171020Y134560D02*
G03X174580Y139230I-4396J7043D01*
G01X177687Y143783D02*
G03X173430Y139573I1713J-5989D01*
G01X174580Y139230D02*
G02X178017Y142629I4820J-1436D01*
G01X178810Y144104D02*
X177687Y143783D01*
G01X178017Y142629D02*
X179140Y142950D01*
G01X180750Y146517D02*
G02X178810Y144104I-2676J165D01*
G01X179140Y142950D02*
G03X181948Y146443I-1066J3732D01*
G01X180942Y149624D02*
X180750Y146517D01*
G01X181948Y146443D02*
X182140Y149550D01*
G01X180114Y151061D02*
G02X180942Y149624I-672J-1344D01*
G01X182140Y149550D02*
G03X180651Y152135I-2698J167D01*
G01X179668Y151285D02*
X180114Y151061D01*
G01X180204Y152359D02*
X180203D01*
G01X180651Y152135D02*
X180204Y152359D01*
G01X179667Y151285D02*
X179668D01*
G01X180651Y152135D02*
X180204Y152359D01*
G01D02*
X180203D01*
G01X179668Y151285D02*
X180114Y151061D01*
G01X180651Y152135D02*
X180204Y152359D01*
G01X179668Y151285D02*
X180114Y151061D01*
G01X179667Y151285D02*
X179668D01*
G01X182140Y149550D02*
G03X180651Y152135I-2698J167D01*
G01X180114Y151061D02*
G02X180942Y149624I-672J-1344D01*
G01X181948Y146443D02*
X182140Y149550D01*
G01X180942Y149624D02*
X180750Y146517D01*
G01X179140Y142950D02*
G03X181948Y146443I-1066J3732D01*
G01X180750Y146517D02*
G02X178810Y144104I-2676J165D01*
G01X178017Y142629D02*
X179140Y142950D01*
G01X178810Y144104D02*
X177687Y143783D01*
G01X174580Y139230D02*
G02X178017Y142629I4820J-1436D01*
G01X177687Y143783D02*
G03X173430Y139573I1713J-5989D01*
G01X171020Y134560D02*
G03X174580Y139230I-4396J7043D01*
G01X173430Y139573D02*
G02X170278Y135513I-6806J2030D01*
G01X169500Y130890D02*
G02X171020Y134560I5190J0D01*
G01X170278Y135513D02*
G03X168300Y130889I4412J-4622D01*
G01X169500Y129300D02*
Y130890D01*
G01X168300Y130889D02*
Y129300D01*
G01X169800Y126800D02*
G02X169500Y129300I10267J2500D01*
G01X168300D02*
G03X168634Y126516I11767J0D01*
G01X170084Y125634D02*
X169800Y126800D01*
G01X168634Y126516D02*
X168957Y125190D01*
G01X176600Y114023D02*
X170084Y125634D01*
G01X168957Y125190D02*
X175453Y113613D01*
G01X175080Y563228D02*
X173111Y565196D01*
G01X175080Y534488D02*
Y563228D01*
G01Y534488D02*
G03X175867Y533700I787J-1D01*
G01X209529D02*
X175867D01*
G01X189214Y-73346D02*
X403466D01*
G01X187245Y-71378D02*
X189214Y-73346D01*
G01X187245Y-52874D02*
Y-71378D01*
G01X251212Y-56165D02*
Y-57698D01*
G01X252412Y-56330D02*
Y-57523D01*
G01X251887Y-53749D02*
X251212Y-56165D01*
G01X289479Y76423D02*
X252412Y-56330D01*
G01X253065Y-49530D02*
X252661Y-50975D01*
G01X289479Y76423D02*
X252412Y-56330D01*
G01X288378Y76943D02*
X253839Y-46756D01*
G01X289479Y76423D02*
X252412Y-56330D01*
G01X260660Y-56083D02*
Y-57361D01*
G01X261860Y-57542D02*
Y-55965D01*
G01X261584Y-52060D02*
X260599Y-56067D01*
G01X261860Y-55965D02*
X293492Y72720D01*
G01X262629Y-47807D02*
X262271Y-49263D01*
G01X261860Y-55965D02*
X293492Y72720D01*
G01X292353Y73115D02*
X263317Y-45010D01*
G01X261860Y-55965D02*
X293492Y72720D01*
G01X252412Y-56330D02*
Y-57523D01*
G01X251212Y-56165D02*
Y-57698D01*
G01X289479Y76423D02*
X252412Y-56330D01*
G01X251887Y-53749D02*
X251212Y-56165D01*
G01X253065Y-49530D02*
X252661Y-50975D01*
G01X288378Y76943D02*
X253839Y-46756D01*
G01X261860Y-55965D02*
X293492Y72720D01*
G01X261584Y-52060D02*
X260599Y-56067D01*
G01X262629Y-47807D02*
X262271Y-49263D01*
G01X292353Y73115D02*
X263317Y-45010D01*
G01X261860Y-57542D02*
Y-55965D01*
G01X260660Y-56083D02*
Y-57361D01*
G01X232686Y-52608D02*
X286897Y126503D01*
G01X234300Y-51434D02*
X233866Y-52870D01*
G01X235569Y-47242D02*
X235135Y-48678D01*
G01X288089Y126296D02*
X236403Y-44486D01*
G01X232314Y-56167D02*
X232686Y-52608D01*
G01X233866Y-52870D02*
X233514Y-56230D01*
G01X232314Y-57208D02*
Y-56167D01*
G01X233514Y-56230D02*
Y-57396D01*
G01X241762Y-56050D02*
X282319Y76166D01*
G01X243507Y-54455D02*
X242962Y-56230D01*
G01X244791Y-50267D02*
X244351Y-51701D01*
G01X283448Y75752D02*
X245636Y-47514D01*
G01X241762Y-57260D02*
Y-56050D01*
G01X242962Y-56230D02*
Y-57244D01*
G01X194518Y-55919D02*
Y-57393D01*
G01X195718Y-56000D02*
Y-57529D01*
G01X195109Y-51549D02*
X194518Y-55919D01*
G01X196300Y-51700D02*
X195718Y-56000D01*
G01X216000Y128000D02*
X195109Y-51549D01*
G01X196519Y-49817D02*
X196300Y-51699D01*
G01X197025Y-45466D02*
X196852Y-46956D01*
G01X217195Y127879D02*
X197358Y-42606D01*
G01X204299Y-53217D02*
X232011Y129952D01*
G01X206076Y-49497D02*
X205492Y-53355D01*
G01X206731Y-45167D02*
X206506Y-46650D01*
G01X233211Y129861D02*
X207162Y-42319D01*
G01X204283Y-53413D02*
X204299Y-53217D01*
G01X205492Y-53355D02*
X205166Y-57447D01*
G01X204222Y-54180D02*
X204283Y-53413D01*
G01X205492Y-53355D02*
X205166Y-57447D01*
G01X203969Y-57350D02*
X204222Y-54180D01*
G01X205492Y-53355D02*
X205166Y-57447D01*
G01X213416Y-56235D02*
Y-56806D01*
G01X214616Y-56306D02*
Y-56806D01*
G01X213715Y-53695D02*
X213416Y-56235D01*
G01X214900Y-53900D02*
X214616Y-56306D01*
G01X213730Y-53633D02*
X213716Y-53694D01*
G01X215235Y-52438D02*
X214900Y-53900D01*
G01X255636Y129496D02*
X213730Y-53633D01*
G01X215235Y-52438D02*
X214900Y-53900D01*
G01X216212Y-48168D02*
X215877Y-49630D01*
G01X256836Y129360D02*
X216854Y-45361D01*
G01X222865Y-56172D02*
Y-57247D01*
G01X224065Y-56328D02*
Y-57376D01*
G01X222904Y-56024D02*
X222865Y-56172D01*
G01X225589Y-50546D02*
X224065Y-56328D01*
G01X270839Y125806D02*
X222904Y-56024D01*
G01X225589Y-50546D02*
X224065Y-56328D01*
G01X226706Y-46310D02*
X226324Y-47761D01*
G01X272000Y125500D02*
X227440Y-43526D01*
G01X233514Y-56230D02*
Y-57396D01*
G01X232314Y-57208D02*
Y-56167D01*
G01X233866Y-52870D02*
X233514Y-56230D01*
G01X232314Y-56167D02*
X232686Y-52608D01*
G01X234300Y-51434D02*
X233866Y-52870D01*
G01X232686Y-52608D02*
X286897Y126503D01*
G01X235569Y-47242D02*
X235135Y-48678D01*
G01X232686Y-52608D02*
X286897Y126503D01*
G01X288089Y126296D02*
X236403Y-44486D01*
G01X232686Y-52608D02*
X286897Y126503D01*
G01X242962Y-56230D02*
Y-57244D01*
G01X241762Y-57260D02*
Y-56050D01*
G01X243507Y-54455D02*
X242962Y-56230D01*
G01X241762Y-56050D02*
X282319Y76166D01*
G01X244791Y-50267D02*
X244351Y-51701D01*
G01X241762Y-56050D02*
X282319Y76166D01*
G01X283448Y75752D02*
X245636Y-47514D01*
G01X241762Y-56050D02*
X282319Y76166D01*
G01X195718Y-56000D02*
Y-57529D01*
G01X194518Y-55919D02*
Y-57393D01*
G01X196300Y-51700D02*
X195718Y-56000D01*
G01X195109Y-51549D02*
X194518Y-55919D01*
G01X196519Y-49817D02*
X196300Y-51699D01*
G01X216000Y128000D02*
X195109Y-51549D01*
G01X197025Y-45466D02*
X196852Y-46956D01*
G01X216000Y128000D02*
X195109Y-51549D01*
G01X217195Y127879D02*
X197358Y-42606D01*
G01X216000Y128000D02*
X195109Y-51549D01*
G01X205492Y-53355D02*
X205166Y-57447D01*
G01X204283Y-53413D02*
X204299Y-53217D01*
G01X204222Y-54180D02*
X204283Y-53413D01*
G01X203969Y-57350D02*
X204222Y-54180D01*
G01X206076Y-49497D02*
X205492Y-53355D01*
G01X204299Y-53217D02*
X232011Y129952D01*
G01X206731Y-45167D02*
X206506Y-46650D01*
G01X204299Y-53217D02*
X232011Y129952D01*
G01X233211Y129861D02*
X207162Y-42319D01*
G01X204299Y-53217D02*
X232011Y129952D01*
G01X214616Y-56306D02*
Y-56806D01*
G01X213416Y-56235D02*
Y-56806D01*
G01X214900Y-53900D02*
X214616Y-56306D01*
G01X213715Y-53695D02*
X213416Y-56235D01*
G01X215235Y-52438D02*
X214900Y-53900D01*
G01X213730Y-53633D02*
X213716Y-53694D01*
G01X255636Y129496D02*
X213730Y-53633D01*
G01X216212Y-48168D02*
X215877Y-49630D01*
G01X255636Y129496D02*
X213730Y-53633D01*
G01X256836Y129360D02*
X216854Y-45361D01*
G01X255636Y129496D02*
X213730Y-53633D01*
G01X224065Y-56328D02*
Y-57376D01*
G01X222865Y-56172D02*
Y-57247D01*
G01X225589Y-50546D02*
X224065Y-56328D01*
G01X222904Y-56024D02*
X222865Y-56172D01*
G01X270839Y125806D02*
X222904Y-56024D01*
G01X226706Y-46310D02*
X226324Y-47761D01*
G01X270839Y125806D02*
X222904Y-56024D01*
G01X272000Y125500D02*
X227440Y-43526D01*
G01X270839Y125806D02*
X222904Y-56024D01*
G01X204900Y88529D02*
X187642Y-364D01*
G01X206100Y88413D02*
X188800Y-700D01*
G01X206100Y88413D02*
X188800Y-700D01*
G01X204900Y88529D02*
X187642Y-364D01*
G01X194221Y78298D02*
X192959Y71142D01*
G01X195440Y78299D02*
X194141Y70934D01*
G01X204900Y115600D02*
Y88529D01*
G01X206100Y115743D02*
Y88413D01*
G01X195440Y78299D02*
X194141Y70934D01*
G01X194221Y78298D02*
X192959Y71142D01*
G01X206100Y115743D02*
Y88413D01*
G01X204900Y115600D02*
Y88529D01*
G01X216266Y131060D02*
X216000Y128000D01*
G01X217467Y131008D02*
X217195Y127879D01*
G01X217698Y134519D02*
G03X216266Y131060I3457J-3457D01*
G01X218421Y133538D02*
G03X217467Y131060I2735J-2475D01*
G01X218144Y134741D02*
X217698Y134519D01*
G01X218673Y133663D02*
X218421Y133538D01*
G01X218683Y133668D02*
X218682D01*
G01X218145Y134741D02*
X218144D01*
G01X218673Y133663D02*
X218421Y133538D01*
G01X233889Y134741D02*
X233890D01*
G01X234418Y133663D02*
X234166Y133538D01*
G01X233443Y134519D02*
X233889Y134741D01*
G01X234418Y133663D02*
X234166Y133538D01*
G01X234428Y133668D02*
X234427D01*
G01X232011Y131062D02*
G02X233443Y134519I4889J0D01*
G01X234166Y133538D02*
G03X233211Y131061I2734J-2477D01*
G01X232011Y131060D02*
G02Y131062I4889J1D01*
G01X234166Y133538D02*
G03X233211Y131061I2734J-2477D01*
G01X232011Y129952D02*
Y131060D01*
G01X233211Y131061D02*
Y129861D01*
G01X255636Y131062D02*
Y129496D01*
G01X256836Y131061D02*
Y129360D01*
G01X257068Y134519D02*
G03X255636Y131062I3457J-3457D01*
G01X257791Y133538D02*
G03X256836Y131061I2734J-2477D01*
G01X257514Y134741D02*
X257068Y134519D01*
G01X258043Y133663D02*
X257791Y133538D01*
G01X258053Y133668D02*
X258052D01*
G01X257515Y134741D02*
X257514D01*
G01X258043Y133663D02*
X257791Y133538D01*
G01X217467Y131008D02*
X217195Y127879D01*
G01X216266Y131060D02*
X216000Y128000D01*
G01X218421Y133538D02*
G03X217467Y131060I2735J-2475D01*
G01X217698Y134519D02*
G03X216266Y131060I3457J-3457D01*
G01X218673Y133663D02*
X218421Y133538D01*
G01X218144Y134741D02*
X217698Y134519D01*
G01X218145Y134741D02*
X218144D01*
G01X218683Y133668D02*
X218682D01*
G01X218144Y134741D02*
X217698Y134519D01*
G01X233211Y131061D02*
Y129861D01*
G01X232011Y129952D02*
Y131060D01*
G01X234166Y133538D02*
G03X233211Y131061I2734J-2477D01*
G01X232011Y131062D02*
G02X233443Y134519I4889J0D01*
G01X232011Y131060D02*
G02Y131062I4889J1D01*
G01X234418Y133663D02*
X234166Y133538D01*
G01X233889Y134741D02*
X233890D01*
G01X233443Y134519D02*
X233889Y134741D01*
G01X234428Y133668D02*
X234427D01*
G01X233443Y134519D02*
X233889Y134741D01*
G01X256836Y131061D02*
Y129360D01*
G01X255636Y131062D02*
Y129496D01*
G01X257791Y133538D02*
G03X256836Y131061I2734J-2477D01*
G01X257068Y134519D02*
G03X255636Y131062I3457J-3457D01*
G01X258043Y133663D02*
X257791Y133538D01*
G01X257514Y134741D02*
X257068Y134519D01*
G01X257515Y134741D02*
X257514D01*
G01X258053Y133668D02*
X258052D01*
G01X257514Y134741D02*
X257068Y134519D01*
G01X201385Y123881D02*
X204900Y115600D01*
G01X202529Y124258D02*
X206060Y115939D01*
G01X201183Y124574D02*
X201385Y123881D01*
G01X202359Y124830D02*
X202510Y124313D01*
G01X200516Y130995D02*
X201176Y124597D01*
G01X201716Y131061D02*
X202359Y124830D01*
G01X201948Y134520D02*
G03X200516Y130995I3457J-3458D01*
G01X202671Y133538D02*
G03X201716Y131061I2734J-2477D01*
G01X202388Y134738D02*
X201948Y134520D01*
G01X202923Y133663D02*
X202671Y133538D01*
G01X202932Y133668D02*
X202923Y133663D01*
G01X202933Y133668D02*
X202932D01*
G01X202394Y134741D02*
X202388Y134738D01*
G01X202923Y133663D02*
X202671Y133538D01*
G01X202395Y134741D02*
X202394D01*
G01X202923Y133663D02*
X202671Y133538D01*
G01X202529Y124258D02*
X206060Y115939D01*
G01X201385Y123881D02*
X204900Y115600D01*
G01X202359Y124830D02*
X202510Y124313D01*
G01X201183Y124574D02*
X201385Y123881D01*
G01X201716Y131061D02*
X202359Y124830D01*
G01X200516Y130995D02*
X201176Y124597D01*
G01X202671Y133538D02*
G03X201716Y131061I2734J-2477D01*
G01X201948Y134520D02*
G03X200516Y130995I3457J-3458D01*
G01X202923Y133663D02*
X202671Y133538D01*
G01X202388Y134738D02*
X201948Y134520D01*
G01X202394Y134741D02*
X202388Y134738D01*
G01X202395Y134741D02*
X202394D01*
G01X202932Y133668D02*
X202923Y133663D01*
G01X202388Y134738D02*
X201948Y134520D01*
G01X202933Y133668D02*
X202932D01*
G01X202388Y134738D02*
X201948Y134520D01*
G01X209529Y533700D02*
G03X210316Y534488I0J787D01*
G01Y563228D02*
Y534488D01*
G01X212284Y565196D02*
X210316Y563228D01*
G01X426536Y565196D02*
X212284D01*
G01X346899Y-54167D02*
Y-56983D01*
G01X345700D02*
Y-57020D01*
G01X345699Y-54166D02*
Y-56983D01*
G01X345770Y-51441D02*
G02X346899Y-54167I-2726J-2726D01*
G01X344921Y-52290D02*
G02X345698Y-54167I-1877J-1877D01*
G01X343440Y-49110D02*
X345770Y-51441D01*
G01X342592Y-49960D02*
X344921Y-52290D01*
G01X343070Y-48217D02*
G03X343440Y-49110I1263J0D01*
G01X341870Y-48218D02*
G03X342592Y-49960I2465J1D01*
G01X343070Y-47641D02*
Y-48217D01*
G01X341870Y-47641D02*
Y-48218D01*
G01X345700Y-56983D02*
Y-57020D01*
G01X346899Y-54167D02*
Y-56983D01*
G01X345699Y-54166D02*
Y-56983D01*
G01X346899Y-54167D02*
Y-56983D01*
G01X344921Y-52290D02*
G02X345698Y-54167I-1877J-1877D01*
G01X345770Y-51441D02*
G02X346899Y-54167I-2726J-2726D01*
G01X342592Y-49960D02*
X344921Y-52290D01*
G01X343440Y-49110D02*
X345770Y-51441D01*
G01X341870Y-48218D02*
G03X342592Y-49960I2465J1D01*
G01X343070Y-48217D02*
G03X343440Y-49110I1263J0D01*
G01X341870Y-47641D02*
Y-48218D01*
G01X343070Y-47641D02*
Y-48217D01*
G01X331670Y-48218D02*
Y-47641D01*
G01X332870Y-48217D02*
Y-47641D01*
G01X332320Y-49790D02*
G02X331670Y-48218I1575J1572D01*
G01X333170Y-48941D02*
G02X332870Y-48217I724J724D01*
G01X332984Y-50454D02*
X332320Y-49790D01*
G01X333833Y-49605D02*
X333170Y-48941D01*
G01X335370Y-51441D02*
G02X332984Y-50454I-2J3374D01*
G01X335370Y-50241D02*
G02X333833Y-49605I-1J2173D01*
G01X337451Y-52322D02*
G03X335370Y-50241I-2081J0D01*
G01X336251Y-52322D02*
G03X335370Y-51441I-881J0D01*
G01X337451Y-52322D02*
G03X335370Y-50241I-2081J0D01*
G01X336251Y-57020D02*
Y-52322D01*
G01X337451Y-56983D02*
Y-52322D01*
G01X326802Y-53542D02*
Y-57020D01*
G01X328002Y-53541D02*
Y-56983D01*
G01X326044Y-51714D02*
G02X326802Y-53542I-1826J-1829D01*
G01X326893Y-50865D02*
G02X328002Y-53541I-2676J-2677D01*
G01X325919Y-51589D02*
X326042Y-51713D01*
G01X326770Y-50741D02*
X326893Y-50865D01*
G01X324598Y-51041D02*
G02X325919Y-51589I-3J-1872D01*
G01X324597Y-49841D02*
G02X326770Y-50741I0J-3073D01*
G01X322363Y-50169D02*
G03X324470Y-51041I2105J2106D01*
G01X323213Y-49321D02*
G03X324470Y-49841I1256J1257D01*
G01X322132Y-49937D02*
X322363Y-50169D01*
G01X322983Y-49090D02*
X323213Y-49321D01*
G01X321432Y-48247D02*
G03X322132Y-49937I2390J0D01*
G01X322632Y-48241D02*
G03X322983Y-49090I1200J-1D01*
G01X321432Y-47875D02*
Y-48247D01*
G01X322632Y-47853D02*
Y-48241D01*
G01X332870Y-48217D02*
Y-47641D01*
G01X331670Y-48218D02*
Y-47641D01*
G01X333170Y-48941D02*
G02X332870Y-48217I724J724D01*
G01X332320Y-49790D02*
G02X331670Y-48218I1575J1572D01*
G01X333833Y-49605D02*
X333170Y-48941D01*
G01X332984Y-50454D02*
X332320Y-49790D01*
G01X335370Y-50241D02*
G02X333833Y-49605I-1J2173D01*
G01X335370Y-51441D02*
G02X332984Y-50454I-2J3374D01*
G01X337451Y-52322D02*
G03X335370Y-50241I-2081J0D01*
G01Y-51441D02*
G02X332984Y-50454I-2J3374D01*
G01X336251Y-52322D02*
G03X335370Y-51441I-881J0D01*
G01X337451Y-56983D02*
Y-52322D01*
G01X336251Y-57020D02*
Y-52322D01*
G01X328002Y-53541D02*
Y-56983D01*
G01X326802Y-53542D02*
Y-57020D01*
G01X326893Y-50865D02*
G02X328002Y-53541I-2676J-2677D01*
G01X326044Y-51714D02*
G02X326802Y-53542I-1826J-1829D01*
G01X326770Y-50741D02*
X326893Y-50865D01*
G01X325919Y-51589D02*
X326042Y-51713D01*
G01X324597Y-49841D02*
G02X326770Y-50741I0J-3073D01*
G01X324598Y-51041D02*
G02X325919Y-51589I-3J-1872D01*
G01X323213Y-49321D02*
G03X324470Y-49841I1256J1257D01*
G01X322363Y-50169D02*
G03X324470Y-51041I2105J2106D01*
G01X322983Y-49090D02*
X323213Y-49321D01*
G01X322132Y-49937D02*
X322363Y-50169D01*
G01X322632Y-48241D02*
G03X322983Y-49090I1200J-1D01*
G01X321432Y-48247D02*
G03X322132Y-49937I2390J0D01*
G01X322632Y-47853D02*
Y-48241D01*
G01X321432Y-47875D02*
Y-48247D01*
G01X270109Y-56103D02*
Y-57014D01*
G01X271309Y-57191D02*
Y-56230D01*
G01X271165Y-51152D02*
X270109Y-56103D01*
G01X271309Y-56230D02*
X298659Y71963D01*
G01X272079Y-46869D02*
X271766Y-48336D01*
G01X271309Y-56230D02*
X298659Y71963D01*
G01X297536Y72452D02*
X272680Y-44052D01*
G01X271309Y-56230D02*
X298659Y71963D01*
G01X281708Y-44859D02*
X301934Y69848D01*
G01X282908Y-44964D02*
X282889Y-45075D01*
G01X303070Y69378D02*
X282908Y-44964D01*
G01X281429Y-46333D02*
X281708Y-44859D01*
G01X282889Y-45075D02*
X280758Y-56338D01*
G01X282908Y-44964D02*
X282889Y-45075D01*
G01X280615Y-50637D02*
X280894Y-49163D01*
G01X282889Y-45075D02*
X280758Y-56338D01*
G01X279558Y-56225D02*
X280080Y-53466D01*
G01X282889Y-45075D02*
X280758Y-56338D01*
G01X279558Y-57052D02*
Y-56225D01*
G01X280758Y-56338D02*
Y-56982D01*
G01X289327Y-52087D02*
X289009Y-57317D01*
G01X290524Y-52182D02*
X290207Y-57389D01*
G01X289472Y-50594D02*
X289327Y-52087D01*
G01X294747Y-8764D02*
X290524Y-52182D01*
G01X289896Y-46235D02*
X289751Y-47728D01*
G01X294747Y-8764D02*
X290524Y-52182D01*
G01X293557Y-8601D02*
X290175Y-43368D01*
G01X294747Y-8764D02*
X290524Y-52182D01*
G01X307051Y67928D02*
X293557Y-8601D01*
G01X308187Y67458D02*
X294747Y-8764D01*
G01X298688Y-55494D02*
X298463Y-57054D01*
G01X299894Y-55542D02*
X299651Y-57225D01*
G01X298759Y-53828D02*
X298702Y-55238D01*
G01X299960Y-53836D02*
X299891Y-55536D01*
G01X298705Y-51881D02*
X298759Y-53828D01*
G01X299382Y-32988D02*
X299960Y-53836D01*
G01X298584Y-47502D02*
X298625Y-49002D01*
G01X299382Y-32988D02*
X299960Y-53836D01*
G01X298181Y-32982D02*
X298504Y-44624D01*
G01X299382Y-32988D02*
X299960Y-53836D01*
G01X299224Y-4887D02*
X298181Y-32982D01*
G01X300421Y-5014D02*
X299382Y-32988D01*
G01X311703Y65874D02*
X299224Y-4887D01*
G01X312839Y65404D02*
X300421Y-5014D01*
G01X307904Y-55595D02*
Y-57218D01*
G01X309104Y-57085D02*
Y-55518D01*
G01X307751Y-54400D02*
X307904Y-55595D01*
G01X309104Y-55518D02*
X308946Y-54281D01*
G01X307561Y-51752D02*
X307751Y-54400D01*
G01X308946Y-54281D02*
X305342Y-4091D01*
G01X307247Y-47383D02*
X307355Y-48879D01*
G01X308946Y-54281D02*
X305342Y-4091D01*
G01X304134Y-4029D02*
X307041Y-44511D01*
G01X308946Y-54281D02*
X305342Y-4091D01*
G01X316006Y63351D02*
X304134Y-4029D01*
G01X305342Y-4091D02*
X317142Y62879D01*
G01X309506Y-1449D02*
X320556Y61236D01*
G01X316204Y29633D02*
X310716Y-1501D01*
G01X311362Y-22257D02*
X309506Y-1449D01*
G01X310716Y-1501D02*
X314400Y-42800D01*
G01X313219Y-43073D02*
X311362Y-22257D01*
G01X310716Y-1501D02*
X314400Y-42800D01*
G01X315126Y-48051D02*
X313219Y-43073D01*
G01X314400Y-42800D02*
X316200Y-47500D01*
G01X317258Y-51289D02*
X315150Y-48088D01*
G01X316200Y-47500D02*
X318392Y-50829D01*
G01X317749Y-53872D02*
X317258Y-51289D01*
G01X318392Y-50829D02*
X318970Y-53864D01*
G01X317353Y-56125D02*
X317749Y-53872D01*
G01X318970Y-53864D02*
X318553Y-56230D01*
G01X317353Y-56969D02*
Y-56125D01*
G01X318553Y-56230D02*
Y-57035D01*
G01X271309Y-56230D02*
X298659Y71963D01*
G01X271165Y-51152D02*
X270109Y-56103D01*
G01X272079Y-46869D02*
X271766Y-48336D01*
G01X297536Y72452D02*
X272680Y-44052D01*
G01X271309Y-57191D02*
Y-56230D01*
G01X270109Y-56103D02*
Y-57014D01*
G01X280758Y-56338D02*
Y-56982D01*
G01X279558Y-57052D02*
Y-56225D01*
G01X282889Y-45075D02*
X280758Y-56338D01*
G01X281429Y-46333D02*
X281708Y-44859D01*
G01X280615Y-50637D02*
X280894Y-49163D01*
G01X279558Y-56225D02*
X280080Y-53466D01*
G01X282908Y-44964D02*
X282889Y-45075D01*
G01X281708Y-44859D02*
X301934Y69848D01*
G01X281429Y-46333D02*
X281708Y-44859D01*
G01X303070Y69378D02*
X282908Y-44964D01*
G01X281708Y-44859D02*
X301934Y69848D01*
G01X290524Y-52182D02*
X290207Y-57389D01*
G01X289327Y-52087D02*
X289009Y-57317D01*
G01X294747Y-8764D02*
X290524Y-52182D01*
G01X289472Y-50594D02*
X289327Y-52087D01*
G01X289896Y-46235D02*
X289751Y-47728D01*
G01X293557Y-8601D02*
X290175Y-43368D01*
G01X308187Y67458D02*
X294747Y-8764D01*
G01X307051Y67928D02*
X293557Y-8601D01*
G01X299894Y-55542D02*
X299651Y-57225D01*
G01X298688Y-55494D02*
X298463Y-57054D01*
G01X299960Y-53836D02*
X299891Y-55536D01*
G01X298759Y-53828D02*
X298702Y-55238D01*
G01X299382Y-32988D02*
X299960Y-53836D01*
G01X298705Y-51881D02*
X298759Y-53828D01*
G01X298584Y-47502D02*
X298625Y-49002D01*
G01X298181Y-32982D02*
X298504Y-44624D01*
G01X300421Y-5014D02*
X299382Y-32988D01*
G01X299224Y-4887D02*
X298181Y-32982D01*
G01X312839Y65404D02*
X300421Y-5014D01*
G01X311703Y65874D02*
X299224Y-4887D01*
G01X305342Y-4091D02*
X317142Y62879D01*
G01X316006Y63351D02*
X304134Y-4029D01*
G01X308946Y-54281D02*
X305342Y-4091D01*
G01X307561Y-51752D02*
X307751Y-54400D01*
G01X307247Y-47383D02*
X307355Y-48879D01*
G01X304134Y-4029D02*
X307041Y-44511D01*
G01X309104Y-55518D02*
X308946Y-54281D01*
G01X307751Y-54400D02*
X307904Y-55595D01*
G01X309104Y-57085D02*
Y-55518D01*
G01X307904Y-55595D02*
Y-57218D01*
G01X318553Y-56230D02*
Y-57035D01*
G01X317353Y-56969D02*
Y-56125D01*
G01X318970Y-53864D02*
X318553Y-56230D01*
G01X317353Y-56125D02*
X317749Y-53872D01*
G01X318392Y-50829D02*
X318970Y-53864D01*
G01X317749Y-53872D02*
X317258Y-51289D01*
G01X316200Y-47500D02*
X318392Y-50829D01*
G01X317258Y-51289D02*
X315150Y-48088D01*
G01X314400Y-42800D02*
X316200Y-47500D01*
G01X315126Y-48051D02*
X313219Y-43073D01*
G01X310716Y-1501D02*
X314400Y-42800D01*
G01X311362Y-22257D02*
X309506Y-1449D01*
G01X313219Y-43073D02*
X311362Y-22257D01*
G01X316204Y29633D02*
X310716Y-1501D01*
G01X309506Y-1449D02*
X320556Y61236D01*
G01X309506Y-1449D02*
X320556Y61236D01*
G01X326070Y113202D02*
X297536Y72452D01*
G01X298659Y71963D02*
X326932Y112340D01*
G01X326028Y102165D02*
X314638Y85897D01*
G01X301934Y69848D02*
X325044Y102853D01*
G01X314638Y85897D02*
X303070Y69377D01*
G01X326028Y102165D02*
X314638Y85897D01*
G01X318105Y83716D02*
X307051Y67928D01*
G01X329990Y98596D02*
X308187Y67458D01*
G01X323556Y91501D02*
X318105Y83716D01*
G01X329990Y98596D02*
X308187Y67458D01*
G01X329364Y99796D02*
X323556Y91501D01*
G01X329990Y98596D02*
X308187Y67458D01*
G01X334049Y106493D02*
X329365Y99796D01*
G01X334912Y105631D02*
X329991Y98596D01*
G01X332629Y95760D02*
X311703Y65874D01*
G01X323227Y80238D02*
X312839Y65403D01*
G01X333613Y95073D02*
X323227Y80238D01*
G01X333666Y95149D02*
X333613Y95073D01*
G01X336626Y101469D02*
X332629Y95761D01*
G01X333666Y95149D02*
X333613Y95073D01*
G01X337488Y100606D02*
X333666Y95149D01*
G01X316224Y63835D02*
X316026Y63359D01*
G01X317135Y62898D02*
X317333Y63374D01*
G01X316274Y63955D02*
X316224Y63835D01*
G01X317135Y62898D02*
X317333Y63374D01*
G01X339016Y96587D02*
X316274Y63955D01*
G01X317333Y63374D02*
X340000Y95900D01*
G01X339115Y96731D02*
X339016Y96587D01*
G01X317333Y63374D02*
X340000Y95900D01*
G01X344866Y101297D02*
X339115Y96731D01*
G01X340000Y95900D02*
X345374Y100168D01*
G01X344519Y94844D02*
X348766Y96831D01*
G01X349131Y95676D02*
X345297Y93882D01*
G01X338878Y87400D02*
X344519Y94844D01*
G01X345297Y93882D02*
X339848Y86693D01*
G01X320556Y61236D02*
X338878Y87400D01*
G01X339848Y86693D02*
X321692Y60766D01*
G01D02*
X316204Y29634D01*
G01X298659Y71963D02*
X326932Y112340D01*
G01X326070Y113202D02*
X297536Y72452D01*
G01X314638Y85897D02*
X303070Y69377D01*
G01X301934Y69848D02*
X325044Y102853D01*
G01X326028Y102165D02*
X314638Y85897D01*
G01X301934Y69848D02*
X325044Y102853D01*
G01X301934Y69848D02*
X325044Y102853D01*
G01X329990Y98596D02*
X308187Y67458D01*
G01X318105Y83716D02*
X307051Y67928D01*
G01X323556Y91501D02*
X318105Y83716D01*
G01X329364Y99796D02*
X323556Y91501D01*
G01X334912Y105631D02*
X329991Y98596D01*
G01X334049Y106493D02*
X329365Y99796D01*
G01X323227Y80238D02*
X312839Y65403D01*
G01X332629Y95760D02*
X311703Y65874D01*
G01X333613Y95073D02*
X323227Y80238D01*
G01X332629Y95760D02*
X311703Y65874D01*
G01X333666Y95149D02*
X333613Y95073D01*
G01X332629Y95760D02*
X311703Y65874D01*
G01X336626Y101469D02*
X332629Y95761D01*
G01X337488Y100606D02*
X333666Y95149D01*
G01X336626Y101469D02*
X332629Y95761D01*
G01X340000Y95900D02*
X345374Y100168D01*
G01X344866Y101297D02*
X339115Y96731D01*
G01X317333Y63374D02*
X340000Y95900D01*
G01X339016Y96587D02*
X316274Y63955D01*
G01X339115Y96731D02*
X339016Y96587D01*
G01X317135Y62898D02*
X317333Y63374D01*
G01X316224Y63835D02*
X316026Y63359D01*
G01X316274Y63955D02*
X316224Y63835D01*
G01X321692Y60766D02*
X316204Y29634D01*
G01X339848Y86693D02*
X321692Y60766D01*
G01X320556Y61236D02*
X338878Y87400D01*
G01X345297Y93882D02*
X339848Y86693D01*
G01X338878Y87400D02*
X344519Y94844D01*
G01X349131Y95676D02*
X345297Y93882D01*
G01X344519Y94844D02*
X348766Y96831D01*
G01X311516Y109989D02*
X288378Y76943D01*
G01X312500Y109300D02*
X289479Y76423D01*
G01X293058Y74662D02*
X292353Y73115D01*
G01X294135Y74130D02*
X294151Y74165D01*
G01X293492Y72720D02*
X294135Y74130D01*
G01X324013Y118892D02*
X293053Y74678D01*
G01X294165Y74172D02*
X324851Y117996D01*
G01X312500Y109300D02*
X289479Y76423D01*
G01X311516Y109989D02*
X288378Y76943D01*
G01X294165Y74172D02*
X324851Y117996D01*
G01X324013Y118892D02*
X293053Y74678D01*
G01X294135Y74130D02*
X294151Y74165D01*
G01X293058Y74662D02*
X292353Y73115D01*
G01X293492Y72720D02*
X294135Y74130D01*
G01X293058Y74662D02*
X292353Y73115D01*
G01X282535Y76668D02*
X294276Y106873D01*
G01X287887Y87123D02*
X283646Y76214D01*
G01X295395Y106439D02*
X287887Y87123D01*
G01X282319Y76166D02*
X282535Y76668D01*
G01X283646Y76214D02*
X283448Y75752D01*
G01X283646Y76214D02*
X283448Y75752D01*
G01X282319Y76166D02*
X282535Y76668D01*
G01X287887Y87123D02*
X283646Y76214D01*
G01X282535Y76668D02*
X294276Y106873D01*
G01X295395Y106439D02*
X287887Y87123D01*
G01X282535Y76668D02*
X294276Y106873D01*
G01X336050Y120190D02*
X326070Y113202D01*
G01X326932Y112340D02*
X336520Y119054D01*
G01X354010Y123357D02*
X336050Y120190D01*
G01X336520Y119054D02*
X354480Y122221D01*
G01X338941Y115780D02*
X367538Y120824D01*
G01X368008Y119688D02*
X339411Y114644D01*
G01X329435Y109123D02*
X338941Y115780D01*
G01X339411Y114644D02*
X330297Y108261D01*
G01X326745Y105283D02*
X329435Y109123D01*
G01X327729Y104594D02*
X327281Y103953D01*
G01X330297Y108261D02*
X327729Y104594D01*
G01X325848Y104001D02*
X326745Y105283D01*
G01X327096Y103689D02*
X326205Y102416D01*
G01X327281Y103953D02*
X327096Y103689D01*
G01X327729Y104594D02*
X327281Y103953D01*
G01X325221Y103104D02*
X325848Y104001D01*
G01X326203Y102413D02*
X326030Y102166D01*
G01X327096Y103689D02*
X326205Y102416D01*
G01X325046Y102856D02*
X325219Y103103D01*
G01X326203Y102413D02*
X326030Y102166D01*
G01X327096Y103689D02*
X326205Y102416D01*
G01X326203Y102413D02*
X326030Y102166D01*
G01X337514Y108919D02*
X334049Y106493D01*
G01X341494Y110242D02*
X334912Y105631D01*
G01X341023Y111378D02*
X337514Y108919D01*
G01X341494Y110242D02*
X334912Y105631D01*
G01X372741Y116971D02*
X341023Y111378D01*
G01X372949Y115788D02*
X341494Y110242D01*
G01X343488Y106270D02*
X336626Y101469D01*
G01X343958Y105134D02*
X337488Y100606D01*
G01X388669Y114239D02*
X343488Y106270D01*
G01X386340Y112609D02*
X343958Y105134D01*
G01X401976Y111368D02*
X344866Y101297D01*
G01X345374Y100168D02*
X402446Y110232D01*
G01X336520Y119054D02*
X354480Y122221D01*
G01X354010Y123357D02*
X336050Y120190D01*
G01X326932Y112340D02*
X336520Y119054D01*
G01X336050Y120190D02*
X326070Y113202D01*
G01X325046Y102856D02*
X325219Y103103D01*
G01X326203Y102413D02*
X326030Y102166D01*
G01X325221Y103104D02*
X325848Y104001D01*
G01X325046Y102856D02*
X325219Y103103D01*
G01X327096Y103689D02*
X326205Y102416D01*
G01X325848Y104001D02*
X326745Y105283D01*
G01X325221Y103104D02*
X325848Y104001D01*
G01X325046Y102856D02*
X325219Y103103D01*
G01X327281Y103953D02*
X327096Y103689D01*
G01X325848Y104001D02*
X326745Y105283D01*
G01X327729Y104594D02*
X327281Y103953D01*
G01X326745Y105283D02*
X329435Y109123D01*
G01X325848Y104001D02*
X326745Y105283D01*
G01X330297Y108261D02*
X327729Y104594D01*
G01X326745Y105283D02*
X329435Y109123D01*
G01X339411Y114644D02*
X330297Y108261D01*
G01X329435Y109123D02*
X338941Y115780D01*
G01X368008Y119688D02*
X339411Y114644D01*
G01X338941Y115780D02*
X367538Y120824D01*
G01X341494Y110242D02*
X334912Y105631D01*
G01X337514Y108919D02*
X334049Y106493D01*
G01X341023Y111378D02*
X337514Y108919D01*
G01X372949Y115788D02*
X341494Y110242D01*
G01X372741Y116971D02*
X341023Y111378D01*
G01X372741Y116971D02*
X341023Y111378D01*
G01X343958Y105134D02*
X337488Y100606D01*
G01X343488Y106270D02*
X336626Y101469D01*
G01X386340Y112609D02*
X343958Y105134D01*
G01X388669Y114239D02*
X343488Y106270D01*
G01X345374Y100168D02*
X402446Y110232D01*
G01X401976Y111368D02*
X344866Y101297D01*
G01X313887Y113375D02*
X311516Y109989D01*
G01X314917Y112752D02*
X312500Y109300D01*
G01X313933Y113441D02*
X313887Y113375D01*
G01X314917Y112752D02*
X312500Y109300D01*
G01X320901Y121298D02*
X314927Y112764D01*
G01X313935Y113444D02*
X313933Y113441D01*
G01X320901Y121298D02*
X314927Y112764D01*
G01X320039Y122160D02*
X313935Y113444D01*
G01X320901Y121298D02*
X314927Y112764D01*
G01X325220Y125786D02*
X320039Y122160D01*
G01X326082Y124924D02*
X320901Y121298D01*
G01X325919Y126783D02*
X325220Y125786D01*
G01X327345Y126727D02*
X326082Y124924D01*
G01X326231Y127230D02*
X325919Y126783D01*
G01X327345Y126727D02*
X326082Y124924D01*
G01X326733Y129309D02*
X326231Y127230D01*
G01X327933Y129166D02*
X327345Y126727D01*
G01X326733Y130627D02*
Y129309D01*
G01X327933Y130626D02*
Y129166D01*
G01X325598Y133537D02*
G02X326732Y130626I-3169J-2911D01*
G01X326321Y134518D02*
G02X327933Y130626I-3892J-3892D01*
G01X325337Y133668D02*
X325598Y133537D01*
G01X325874Y134742D02*
X326321Y134518D01*
G01X325873Y134742D02*
X325874D01*
G01X334349Y125141D02*
X324013Y118892D01*
G01X324851Y117996D02*
X334851Y124042D01*
G01X337129Y126042D02*
X334349Y125141D01*
G01X334851Y124042D02*
X337500Y124900D01*
G01X338991Y126647D02*
X337129Y126042D01*
G01X337500Y124900D02*
X341500Y126200D01*
G01X340854Y127252D02*
X338991Y126647D01*
G01X337500Y124900D02*
X341500Y126200D01*
G01X341889Y128291D02*
X340854Y127252D01*
G01X341500Y126200D02*
X342963Y127667D01*
G01X342258Y129627D02*
X341889Y128291D01*
G01X342963Y127667D02*
X343458Y129464D01*
G01X342258Y131164D02*
Y129627D01*
G01X343458Y129464D02*
Y131163D01*
G01X341344Y133538D02*
G02X342257Y131163I-2632J-2375D01*
G01X343458D02*
G03X342068Y134519I-4746J0D01*
G01X341084Y133668D02*
X341344Y133538D01*
G01X341622Y134741D02*
X341621D01*
G01X342068Y134519D02*
X341622Y134741D01*
G01X341083Y133668D02*
X341084D01*
G01X342068Y134519D02*
X341622Y134741D01*
G01X314917Y112752D02*
X312500Y109300D01*
G01X313887Y113375D02*
X311516Y109989D01*
G01X313933Y113441D02*
X313887Y113375D01*
G01X320901Y121298D02*
X314927Y112764D01*
G01X313933Y113441D02*
X313887Y113375D01*
G01X313935Y113444D02*
X313933Y113441D01*
G01X320039Y122160D02*
X313935Y113444D01*
G01X326082Y124924D02*
X320901Y121298D01*
G01X325220Y125786D02*
X320039Y122160D01*
G01X327345Y126727D02*
X326082Y124924D01*
G01X325919Y126783D02*
X325220Y125786D01*
G01X326231Y127230D02*
X325919Y126783D01*
G01X327933Y129166D02*
X327345Y126727D01*
G01X326733Y129309D02*
X326231Y127230D01*
G01X327933Y130626D02*
Y129166D01*
G01X326733Y130627D02*
Y129309D01*
G01X326321Y134518D02*
G02X327933Y130626I-3892J-3892D01*
G01X325598Y133537D02*
G02X326732Y130626I-3169J-2911D01*
G01X325874Y134742D02*
X326321Y134518D01*
G01X325337Y133668D02*
X325598Y133537D01*
G01X325873Y134742D02*
X325874D01*
G01X325337Y133668D02*
X325598Y133537D01*
G01X341622Y134741D02*
X341621D01*
G01X341084Y133668D02*
X341344Y133538D01*
G01X342068Y134519D02*
X341622Y134741D01*
G01X341084Y133668D02*
X341344Y133538D01*
G01X341083Y133668D02*
X341084D01*
G01X343458Y131163D02*
G03X342068Y134519I-4746J0D01*
G01X341344Y133538D02*
G02X342257Y131163I-2632J-2375D01*
G01X343458Y129464D02*
Y131163D01*
G01X342258Y131164D02*
Y129627D01*
G01X342963Y127667D02*
X343458Y129464D01*
G01X342258Y129627D02*
X341889Y128291D01*
G01X341500Y126200D02*
X342963Y127667D01*
G01X341889Y128291D02*
X340854Y127252D01*
G01X337500Y124900D02*
X341500Y126200D01*
G01X338991Y126647D02*
X337129Y126042D01*
G01X340854Y127252D02*
X338991Y126647D01*
G01X334851Y124042D02*
X337500Y124900D01*
G01X337129Y126042D02*
X334349Y125141D01*
G01X324851Y117996D02*
X334851Y124042D01*
G01X334349Y125141D02*
X324013Y118892D01*
G01X289009Y134741D02*
X289010D01*
G01X289538Y133663D02*
X289286Y133538D01*
G01X288563Y134519D02*
X289009Y134741D01*
G01X289538Y133663D02*
X289286Y133538D01*
G01X289548Y133668D02*
X289547D01*
G01X287132Y131173D02*
G02X288563Y134519I4888J-111D01*
G01X288332Y131146D02*
G03X288331Y131061I3688J-86D01*
G01X289286Y133538D02*
G03X288332Y131146I2734J-2477D01*
G01X287130Y131122D02*
G02Y131158I4890J18D01*
G01X289286Y133538D02*
G03X288332Y131146I2734J-2477D01*
G01X287064Y129791D02*
X287130Y131078D01*
G01X288331Y131061D02*
X288089Y126296D01*
G01X286897Y126503D02*
X287064Y129791D01*
G01X288331Y131061D02*
X288089Y126296D01*
G01X304146Y134344D02*
G02X304313Y134519I3619J-3287D01*
G01X305036Y133538D02*
G03X304081Y131061I2734J-2477D01*
G01X302881Y131062D02*
G02X304146Y134344I4889J0D01*
G01X305036Y133538D02*
G03X304081Y131061I2734J-2477D01*
G01X302881Y129461D02*
Y131062D01*
G01X304081Y131061D02*
Y129355D01*
G01X302737Y128645D02*
X302881Y129461D01*
G01X304081Y129355D02*
X303873Y128175D01*
G01X302547Y128150D02*
X302744Y128626D01*
G01X303853Y128167D02*
X303656Y127691D01*
G01X294276Y106873D02*
X302542Y128138D01*
G01X303656Y127691D02*
X295395Y106439D01*
G01X271381Y129253D02*
X270839Y125806D01*
G01X272581Y129159D02*
X272015Y125559D01*
G01X271381Y131062D02*
Y129253D01*
G01X272581Y131061D02*
Y129159D01*
G01X272239Y133828D02*
G03X271381Y131062I4030J-2766D01*
G01X273229Y133149D02*
G03X272581Y131061I3041J-2088D01*
G01X272646Y134343D02*
G03X272239Y133828I3623J-3282D01*
G01X273229Y133149D02*
G03X272581Y131061I3041J-2088D01*
G01X288331D02*
X288089Y126296D01*
G01X287064Y129791D02*
X287130Y131078D01*
G01X286897Y126503D02*
X287064Y129791D01*
G01X288332Y131146D02*
G03X288331Y131061I3688J-86D01*
G01X287132Y131173D02*
G02X288563Y134519I4888J-111D01*
G01X289286Y133538D02*
G03X288332Y131146I2734J-2477D01*
G01X287132Y131173D02*
G02X288563Y134519I4888J-111D01*
G01X287130Y131122D02*
G02Y131158I4890J18D01*
G01X289538Y133663D02*
X289286Y133538D01*
G01X289009Y134741D02*
X289010D01*
G01X288563Y134519D02*
X289009Y134741D01*
G01X289548Y133668D02*
X289547D01*
G01X288563Y134519D02*
X289009Y134741D01*
G01X303656Y127691D02*
X295395Y106439D01*
G01X294276Y106873D02*
X302542Y128138D01*
G01X303853Y128167D02*
X303656Y127691D01*
G01X302547Y128150D02*
X302744Y128626D01*
G01X304081Y129355D02*
X303873Y128175D01*
G01X302737Y128645D02*
X302881Y129461D01*
G01X304081Y131061D02*
Y129355D01*
G01X302881Y129461D02*
Y131062D01*
G01X305036Y133538D02*
G03X304081Y131061I2734J-2477D01*
G01X304146Y134344D02*
G02X304313Y134519I3619J-3287D01*
G01X302881Y131062D02*
G02X304146Y134344I4889J0D01*
G01X272581Y129159D02*
X272015Y125559D01*
G01X271381Y129253D02*
X270839Y125806D01*
G01X272581Y131061D02*
Y129159D01*
G01X271381Y131062D02*
Y129253D01*
G01X273229Y133149D02*
G03X272581Y131061I3041J-2088D01*
G01X272239Y133828D02*
G03X271381Y131062I4030J-2766D01*
G01X272646Y134343D02*
G03X272239Y133828I3623J-3282D01*
G01X343926Y205060D02*
X377838Y181317D01*
G01X378308Y182453D02*
X344789Y205922D01*
G01X343383Y205838D02*
X343926Y205060D01*
G01X344442Y206418D02*
X344317Y206598D01*
G01X344789Y205922D02*
X344442Y206418D01*
G01X343185Y206121D02*
X343383Y205838D01*
G01X344442Y206418D02*
X344317Y206598D01*
G01X342283Y210897D02*
X343185Y206121D01*
G01X344317Y206598D02*
X343484Y211009D01*
G01X341345Y213440D02*
G02X342283Y211002I-2697J-2437D01*
G01X343484Y211009D02*
G03X342068Y214421I-4835J-7D01*
G01X341093Y213565D02*
X341345Y213440D01*
G01X341622Y214643D02*
X341621D01*
G01X342068Y214421D02*
X341622Y214643D01*
G01X341083Y213570D02*
X341084D01*
G01X342068Y214421D02*
X341622Y214643D01*
G01X325338Y213570D02*
X325337D01*
G01X325887Y214637D02*
X326321Y214420D01*
G01X325349Y213564D02*
X325338Y213570D01*
G01X325887Y214637D02*
X326321Y214420D01*
G01X325597Y213440D02*
X325349Y213564D01*
G01X325887Y214637D02*
X326321Y214420D01*
G01X325874Y214644D02*
X325887Y214637D01*
G01X325873Y214644D02*
X325874D01*
G01X326573Y210914D02*
G03X325597Y213440I-3757J0D01*
G01X326321Y214420D02*
G02X327773Y210915I-3505J-3505D01*
G01X326573Y208734D02*
Y210914D01*
G01X327773Y210915D02*
Y208840D01*
G01X326831Y207271D02*
X326573Y208734D01*
G01X327773Y208840D02*
X327967Y207741D01*
G01X328272Y205212D02*
X326831Y207271D01*
G01X327967Y207741D02*
X329134Y206074D01*
G01X367119Y178011D02*
X328272Y205212D01*
G01X329134Y206074D02*
X369112Y178081D01*
G01X329134Y206074D02*
X369112Y178081D01*
G01X341622Y214643D02*
X341621D01*
G01X341093Y213565D02*
X341345Y213440D01*
G01X342068Y214421D02*
X341622Y214643D01*
G01X341093Y213565D02*
X341345Y213440D01*
G01X341083Y213570D02*
X341084D01*
G01X343484Y211009D02*
G03X342068Y214421I-4835J-7D01*
G01X341345Y213440D02*
G02X342283Y211002I-2697J-2437D01*
G01X344317Y206598D02*
X343484Y211009D01*
G01X342283Y210897D02*
X343185Y206121D01*
G01X344442Y206418D02*
X344317Y206598D01*
G01X343383Y205838D02*
X343926Y205060D01*
G01X343185Y206121D02*
X343383Y205838D01*
G01X344789Y205922D02*
X344442Y206418D01*
G01X343383Y205838D02*
X343926Y205060D01*
G01X378308Y182453D02*
X344789Y205922D01*
G01X343926Y205060D02*
X377838Y181317D01*
G01X329134Y206074D02*
X369112Y178081D01*
G01X367119Y178011D02*
X328272Y205212D01*
G01X327967Y207741D02*
X329134Y206074D01*
G01X328272Y205212D02*
X326831Y207271D01*
G01X327773Y208840D02*
X327967Y207741D01*
G01X326831Y207271D02*
X326573Y208734D01*
G01X327773Y210915D02*
Y208840D01*
G01X326573Y208734D02*
Y210914D01*
G01X326321Y214420D02*
G02X327773Y210915I-3505J-3505D01*
G01X326573Y210914D02*
G03X325597Y213440I-3757J0D01*
G01X325887Y214637D02*
X326321Y214420D01*
G01X325338Y213570D02*
X325337D01*
G01X325349Y213564D02*
X325338Y213570D01*
G01X325597Y213440D02*
X325349Y213564D01*
G01X325874Y214644D02*
X325887Y214637D01*
G01X325597Y213440D02*
X325349Y213564D01*
G01X325873Y214644D02*
X325874D01*
G01X325597Y213440D02*
X325349Y213564D01*
G01X405434Y-71378D02*
Y-42638D01*
G01X403466Y-73346D02*
X405434Y-71378D01*
G01X392943Y-56983D02*
Y-48541D01*
G01X394143Y-56983D02*
Y-48541D01*
G01X392944Y-57020D02*
Y-56983D01*
G01X394143D02*
Y-48541D01*
G01X382697Y-49572D02*
G02X383495Y-56983I-34031J-7413D01*
G01X383870Y-49317D02*
G02X384695Y-56983I-35204J-7666D01*
G01X382670Y-47641D02*
Y-49318D01*
G01X383870Y-47641D02*
Y-49317D01*
G01X374046Y-53641D02*
Y-57020D01*
G01X375246Y-53641D02*
Y-56983D01*
G01X373366Y-51831D02*
G02X374046Y-53641I-2071J-1811D01*
G01X374270Y-51041D02*
G02X375246Y-53641I-2975J-2600D01*
G01X372476Y-49014D02*
G03X373366Y-51831I3666J-391D01*
G01X373670Y-49141D02*
G03X374270Y-51041I2472J-264D01*
G01X372470Y-47641D02*
Y-48541D01*
G01X373670Y-47641D02*
Y-49141D01*
G01X362270Y-48217D02*
Y-47641D01*
G01X363470Y-48217D02*
Y-47641D01*
G01X363062Y-50131D02*
G02X362270Y-48217I1915J1913D01*
G01X363911Y-49282D02*
G02X363470Y-48217I1065J1065D01*
G01X363421Y-50490D02*
X363062Y-50131D01*
G01X364270Y-49641D02*
X363911Y-49282D01*
G01X364596Y-53328D02*
G03X363421Y-50490I-4013J1D01*
G01X365797Y-53328D02*
G03X364270Y-49641I-5214J0D01*
G01X364597Y-57020D02*
Y-53327D01*
G01X365797Y-56983D02*
Y-53328D01*
G01X352070Y-48217D02*
Y-47641D01*
G01X353270Y-48217D02*
Y-47641D01*
G01X352862Y-50131D02*
G02X352070Y-48217I1915J1913D01*
G01X353711Y-49282D02*
G02X353270Y-48217I1065J1065D01*
G01X354421Y-51690D02*
X352862Y-50131D01*
G01X355270Y-50841D02*
X353711Y-49282D01*
G01X355149Y-53448D02*
G03X354421Y-51690I-2486J0D01*
G01X356348Y-53444D02*
G03X355270Y-50841I-3681J0D01*
G01X355149Y-57020D02*
Y-53448D01*
G01X356348Y-56983D02*
Y-53444D01*
G01X394143Y-56983D02*
Y-48541D01*
G01X392943Y-56983D02*
Y-48541D01*
G01X392944Y-57020D02*
Y-56983D01*
G01X383870Y-49317D02*
G02X384695Y-56983I-35204J-7666D01*
G01X382697Y-49572D02*
G02X383495Y-56983I-34031J-7413D01*
G01X383870Y-47641D02*
Y-49317D01*
G01X382670Y-47641D02*
Y-49318D01*
G01X375246Y-53641D02*
Y-56983D01*
G01X374046Y-53641D02*
Y-57020D01*
G01X374270Y-51041D02*
G02X375246Y-53641I-2975J-2600D01*
G01X373366Y-51831D02*
G02X374046Y-53641I-2071J-1811D01*
G01X373670Y-49141D02*
G03X374270Y-51041I2472J-264D01*
G01X372476Y-49014D02*
G03X373366Y-51831I3666J-391D01*
G01X373670Y-47641D02*
Y-49141D01*
G01X372470Y-47641D02*
Y-48541D01*
G01X363470Y-48217D02*
Y-47641D01*
G01X362270Y-48217D02*
Y-47641D01*
G01X363911Y-49282D02*
G02X363470Y-48217I1065J1065D01*
G01X363062Y-50131D02*
G02X362270Y-48217I1915J1913D01*
G01X364270Y-49641D02*
X363911Y-49282D01*
G01X363421Y-50490D02*
X363062Y-50131D01*
G01X365797Y-53328D02*
G03X364270Y-49641I-5214J0D01*
G01X364596Y-53328D02*
G03X363421Y-50490I-4013J1D01*
G01X365797Y-56983D02*
Y-53328D01*
G01X364597Y-57020D02*
Y-53327D01*
G01X353270Y-48217D02*
Y-47641D01*
G01X352070Y-48217D02*
Y-47641D01*
G01X353711Y-49282D02*
G02X353270Y-48217I1065J1065D01*
G01X352862Y-50131D02*
G02X352070Y-48217I1915J1913D01*
G01X355270Y-50841D02*
X353711Y-49282D01*
G01X354421Y-51690D02*
X352862Y-50131D01*
G01X356348Y-53444D02*
G03X355270Y-50841I-3681J0D01*
G01X355149Y-53448D02*
G03X354421Y-51690I-2486J0D01*
G01X356348Y-56983D02*
Y-53444D01*
G01X355149Y-57020D02*
Y-53448D01*
G01X406221Y-41850D02*
X439883D01*
G01X406221D02*
G03X405434Y-42638I1J-788D01*
G01X348766Y96831D02*
X408250Y107320D01*
G01X408720Y106184D02*
X349131Y95676D01*
G01X408720Y106184D02*
X349131Y95676D01*
G01X348766Y96831D02*
X408250Y107320D01*
G01X390201Y184102D02*
X459431Y171894D01*
G01X459901Y173030D02*
X390671Y185238D01*
G01X459901Y173030D02*
X390671Y185238D01*
G01X390201Y184102D02*
X459431Y171894D01*
G01X380807Y180792D02*
X453905Y167903D01*
G01X454113Y169085D02*
X383001Y181625D01*
G01X368642Y176945D02*
X367119Y178011D01*
G01X370881Y176550D02*
X368642Y176945D01*
G01X369112Y178081D02*
X457092Y162568D01*
G01X456622Y161432D02*
X370881Y176550D01*
G01X369112Y178081D02*
X457092Y162568D01*
G01X380807Y180792D02*
X453905Y167903D01*
G01X454113Y169085D02*
X383001Y181625D01*
G01X380807Y180792D02*
X453905Y167903D01*
G01X369112Y178081D02*
X457092Y162568D01*
G01X370881Y176550D02*
X368642Y176945D01*
G01X456622Y161432D02*
X370881Y176550D01*
G01X368642Y176945D02*
X367119Y178011D01*
G01X356500Y125100D02*
X354010Y123357D01*
G01X354480Y122221D02*
X357362Y124238D01*
G01X357746Y126880D02*
X356500Y125100D01*
G01X357362Y124238D02*
X358882Y126409D01*
G01X358100Y128880D02*
X357746Y126880D01*
G01X358882Y126409D02*
X359302Y128785D01*
G01X358049Y131826D02*
X358100Y128880D01*
G01X359302Y128785D02*
X359251Y131742D01*
G01X357279Y133444D02*
G02X358065Y131927I-646J-1297D01*
G01X359251Y131744D02*
G03X357816Y134518I-2618J404D01*
G01X356844Y133662D02*
X357279Y133444D01*
G01X357369Y134742D02*
X357368D01*
G01X357382Y134735D02*
X357369Y134742D01*
G01X357816Y134518D02*
X357382Y134735D01*
G01X356833Y133668D02*
X356844Y133662D01*
G01X357816Y134518D02*
X357382Y134735D01*
G01X356832Y133668D02*
X356833D01*
G01X357816Y134518D02*
X357382Y134735D01*
G01X372579Y133668D02*
X372578D01*
G01X373117Y134741D02*
X373563Y134519D01*
G01X372841Y133537D02*
X372579Y133668D01*
G01X373117Y134741D02*
X373563Y134519D01*
G01X373116Y134741D02*
X373117D01*
G01X373904Y130798D02*
G03X372841Y133537I-4061J0D01*
G01X373728Y134347D02*
G02X375104Y130799I-3885J-3548D01*
G01X373564Y134518D02*
G02X373728Y134347I-3714J-3726D01*
G01X373904Y129499D02*
Y130798D01*
G01X375104Y130799D02*
Y129309D01*
G01X373587Y127702D02*
X373904Y129499D01*
G01X375086Y129291D02*
X374723Y127232D01*
G01X372994Y126232D02*
X373595Y127682D01*
G01X374403Y126496D02*
X374053Y125651D01*
G01X374704Y127223D02*
X374403Y126496D01*
G01X370811Y123114D02*
X372994Y126232D01*
G01X373431Y124763D02*
X371673Y122252D01*
G01X374053Y125651D02*
X373431Y124763D01*
G01X367538Y120824D02*
X370811Y123114D01*
G01X371673Y122252D02*
X368008Y119688D01*
G01X373197Y115861D02*
X372949Y115788D01*
G01X382300Y120900D02*
X372741Y116971D01*
G01X377976Y117825D02*
X373197Y115861D01*
G01X382893Y119845D02*
X377976Y117825D01*
G01X386938Y124310D02*
X382300Y120900D01*
G01X387811Y123461D02*
X382893Y119845D01*
G01X389052Y127361D02*
X386938Y124310D01*
G01X390190Y126894D02*
X387811Y123461D01*
G01X389663Y130869D02*
X389052Y127361D01*
G01X390865Y130772D02*
X390190Y126894D01*
G01X388591Y133538D02*
G02X389663Y130869I-3026J-2765D01*
G01X389311Y134522D02*
G02X390865Y130772I-3745J-3749D01*
G01X388461Y133602D02*
X388591Y133538D01*
G01X389044Y134653D02*
X389311Y134522D01*
G01X388867Y134741D02*
X389044Y134653D01*
G01X388333Y133666D02*
X388461Y133602D01*
G01X388867Y134741D02*
X389044Y134653D01*
G01X390279Y114523D02*
X388669Y114239D01*
G01X390750Y113387D02*
X386342Y112610D01*
G01X395594Y118244D02*
X390279Y114523D01*
G01X396283Y117260D02*
X390750Y113387D01*
G01X400535Y121703D02*
X395594Y118244D01*
G01X401397Y120841D02*
X396283Y117260D01*
G01X404925Y127971D02*
X400535Y121703D01*
G01X406061Y127501D02*
X401397Y120841D01*
G01X405095Y128939D02*
X404925Y127971D01*
G01X406295Y128834D02*
X406061Y127501D01*
G01X405095Y131537D02*
Y128939D01*
G01X406295Y131536D02*
Y128834D01*
G01X404334Y133539D02*
G02X405095Y131537I-2255J-2003D01*
G01X405060Y134518D02*
G02X406295Y131536I-2981J-2981D01*
G01X404077Y133668D02*
X404334Y133539D01*
G01X404745Y134676D02*
X405060Y134518D01*
G01X404617Y134740D02*
X404745Y134676D01*
G01X404618Y134740D02*
X404617D01*
G01X404614Y134742D02*
X404618Y134740D01*
G01X404613Y134742D02*
X404614D01*
G01X409713Y116785D02*
X401976Y111368D01*
G01X402446Y110232D02*
X410431Y115822D01*
G01X418878Y124060D02*
X409713Y116785D01*
G01X410431Y115822D02*
X419891Y123332D01*
G01X421155Y130367D02*
X418878Y124060D01*
G01X419891Y123332D02*
X422355Y130157D01*
G01X421155Y130969D02*
Y130367D01*
G01X422355Y130157D02*
Y130997D01*
G01X420086Y133537D02*
G02X421155Y130969I-3025J-2766D01*
G01X422355Y130997D02*
G03X420809Y134518I-5294J-225D01*
G01X419824Y133668D02*
X420086Y133537D01*
G01X420363Y134741D02*
X420361D01*
G01X420809Y134518D02*
X420363Y134741D01*
G01X419823Y133668D02*
X419824D01*
G01X420809Y134518D02*
X420363Y134741D01*
G01X435409Y124872D02*
X408720Y106184D01*
G01X435409Y124872D02*
X408720Y106184D01*
G01X435409Y124872D02*
X408720Y106184D01*
G01X435409Y124872D02*
X408720Y106184D01*
G01X408250Y107320D02*
X427544Y120830D01*
G01X435409Y124872D02*
X408720Y106184D01*
G01X357369Y134742D02*
X357368D01*
G01X356844Y133662D02*
X357279Y133444D01*
G01X357382Y134735D02*
X357369Y134742D01*
G01X356844Y133662D02*
X357279Y133444D01*
G01X357816Y134518D02*
X357382Y134735D01*
G01X356844Y133662D02*
X357279Y133444D01*
G01X356833Y133668D02*
X356844Y133662D01*
G01X356832Y133668D02*
X356833D01*
G01X359251Y131744D02*
G03X357816Y134518I-2618J404D01*
G01X357279Y133444D02*
G02X358065Y131927I-646J-1297D01*
G01X359302Y128785D02*
X359251Y131742D01*
G01X358049Y131826D02*
X358100Y128880D01*
G01X358882Y126409D02*
X359302Y128785D01*
G01X358100Y128880D02*
X357746Y126880D01*
G01X357362Y124238D02*
X358882Y126409D01*
G01X357746Y126880D02*
X356500Y125100D01*
G01X354480Y122221D02*
X357362Y124238D01*
G01X356500Y125100D02*
X354010Y123357D01*
G01X371673Y122252D02*
X368008Y119688D01*
G01X367538Y120824D02*
X370811Y123114D01*
G01X373431Y124763D02*
X371673Y122252D01*
G01X370811Y123114D02*
X372994Y126232D01*
G01X374053Y125651D02*
X373431Y124763D01*
G01X370811Y123114D02*
X372994Y126232D01*
G01X374403Y126496D02*
X374053Y125651D01*
G01X372994Y126232D02*
X373595Y127682D01*
G01X374704Y127223D02*
X374403Y126496D01*
G01X372994Y126232D02*
X373595Y127682D01*
G01X375086Y129291D02*
X374723Y127232D01*
G01X373587Y127702D02*
X373904Y129499D01*
G01X375104Y130799D02*
Y129309D01*
G01X373904Y129499D02*
Y130798D01*
G01X373728Y134347D02*
G02X375104Y130799I-3885J-3548D01*
G01X373904Y130798D02*
G03X372841Y133537I-4061J0D01*
G01X373564Y134518D02*
G02X373728Y134347I-3714J-3726D01*
G01X373904Y130798D02*
G03X372841Y133537I-4061J0D01*
G01X373117Y134741D02*
X373563Y134519D01*
G01X372579Y133668D02*
X372578D01*
G01X372841Y133537D02*
X372579Y133668D01*
G01X373116Y134741D02*
X373117D01*
G01X372841Y133537D02*
X372579Y133668D01*
G01X373197Y115861D02*
X372949Y115788D01*
G01X377976Y117825D02*
X373197Y115861D01*
G01X382300Y120900D02*
X372741Y116971D01*
G01X382893Y119845D02*
X377976Y117825D01*
G01X382300Y120900D02*
X372741Y116971D01*
G01X387811Y123461D02*
X382893Y119845D01*
G01X386938Y124310D02*
X382300Y120900D01*
G01X390190Y126894D02*
X387811Y123461D01*
G01X389052Y127361D02*
X386938Y124310D01*
G01X390865Y130772D02*
X390190Y126894D01*
G01X389663Y130869D02*
X389052Y127361D01*
G01X389311Y134522D02*
G02X390865Y130772I-3745J-3749D01*
G01X388591Y133538D02*
G02X389663Y130869I-3026J-2765D01*
G01X389044Y134653D02*
X389311Y134522D01*
G01X388461Y133602D02*
X388591Y133538D01*
G01X388867Y134741D02*
X389044Y134653D01*
G01X388461Y133602D02*
X388591Y133538D01*
G01X388333Y133666D02*
X388461Y133602D01*
G01X390750Y113387D02*
X386342Y112610D01*
G01X390279Y114523D02*
X388669Y114239D01*
G01X396283Y117260D02*
X390750Y113387D01*
G01X395594Y118244D02*
X390279Y114523D01*
G01X401397Y120841D02*
X396283Y117260D01*
G01X400535Y121703D02*
X395594Y118244D01*
G01X406061Y127501D02*
X401397Y120841D01*
G01X404925Y127971D02*
X400535Y121703D01*
G01X406295Y128834D02*
X406061Y127501D01*
G01X405095Y128939D02*
X404925Y127971D01*
G01X406295Y131536D02*
Y128834D01*
G01X405095Y131537D02*
Y128939D01*
G01X405060Y134518D02*
G02X406295Y131536I-2981J-2981D01*
G01X404334Y133539D02*
G02X405095Y131537I-2255J-2003D01*
G01X404745Y134676D02*
X405060Y134518D01*
G01X404077Y133668D02*
X404334Y133539D01*
G01X404617Y134740D02*
X404745Y134676D01*
G01X404077Y133668D02*
X404334Y133539D01*
G01X404618Y134740D02*
X404617D01*
G01X404077Y133668D02*
X404334Y133539D01*
G01X404614Y134742D02*
X404618Y134740D01*
G01X404077Y133668D02*
X404334Y133539D01*
G01X404613Y134742D02*
X404614D01*
G01X404077Y133668D02*
X404334Y133539D01*
G01X420363Y134741D02*
X420361D01*
G01X419824Y133668D02*
X420086Y133537D01*
G01X420809Y134518D02*
X420363Y134741D01*
G01X419824Y133668D02*
X420086Y133537D01*
G01X419823Y133668D02*
X419824D01*
G01X422355Y130997D02*
G03X420809Y134518I-5294J-225D01*
G01X420086Y133537D02*
G02X421155Y130969I-3025J-2766D01*
G01X422355Y130157D02*
Y130997D01*
G01X421155Y130969D02*
Y130367D01*
G01X419891Y123332D02*
X422355Y130157D01*
G01X421155Y130367D02*
X418878Y124060D01*
G01X410431Y115822D02*
X419891Y123332D01*
G01X418878Y124060D02*
X409713Y116785D01*
G01X402446Y110232D02*
X410431Y115822D01*
G01X409713Y116785D02*
X401976Y111368D01*
G01X435409Y124872D02*
X408720Y106184D01*
G01X408250Y107320D02*
X427544Y120830D01*
G01X422964Y205501D02*
X435553Y196686D01*
G01X423826Y206363D02*
X436023Y197822D01*
G01X421264Y207930D02*
X422964Y205501D01*
G01X422400Y208400D02*
X423826Y206363D01*
G01X421033Y209243D02*
X421264Y207930D01*
G01X422233Y209348D02*
X422400Y208400D01*
G01X421033Y210980D02*
Y209243D01*
G01X422233Y210981D02*
Y209348D01*
G01X420085Y213440D02*
G02X421033Y210980I-2717J-2460D01*
G01X420808Y214421D02*
G02X422233Y210981I-3440J-3440D01*
G01X419833Y213565D02*
X420085Y213440D01*
G01X420362Y214643D02*
X420808Y214421D01*
G01X420361Y214643D02*
X420362D01*
G01X419823Y213570D02*
X419824D01*
G01X420362Y214643D02*
X420808Y214421D01*
G01X466063Y187139D02*
X423681Y194611D01*
G01X423211Y193475D02*
X465592Y186003D01*
G01X466063Y187139D02*
X423681Y194611D01*
G01X407525Y204459D02*
X423211Y193475D01*
G01X423681Y194611D02*
X408387Y205321D01*
G01X405950Y206710D02*
X407525Y204459D01*
G01X408387Y205321D02*
X407086Y207180D01*
G01X405521Y209142D02*
X405950Y206710D01*
G01X407086Y207180D02*
X406721Y209248D01*
G01X405521Y210523D02*
Y209142D01*
G01X406721Y209248D02*
Y210523D01*
G01X404346Y213435D02*
G02X405521Y210523I-3025J-2914D01*
G01X405212Y214268D02*
G03X405139Y214342I-3881J-3756D01*
G01X406721Y210523D02*
G03X405212Y214268I-5401J0D01*
G01X404078Y213570D02*
X404343Y213437D01*
G01X404614Y214644D02*
X404613D01*
G01X405012Y214445D02*
X404614Y214644D01*
G01X404077Y213570D02*
X404078D01*
G01X405012Y214445D02*
X404614Y214644D01*
G01X388329Y213570D02*
X388328D01*
G01X389313Y214421D02*
X388867Y214643D01*
G01X388597Y213436D02*
X388329Y213570D01*
G01X388867Y214643D02*
X388866D01*
G01X389313Y214421D02*
X388867Y214643D01*
G01X389599Y210900D02*
G03X388597Y213436I-3710J0D01*
G01X389473Y214257D02*
G03X389362Y214372I-3588J-3353D01*
G01X390800Y210900D02*
G03X389473Y214257I-4911J0D01*
G01X390723Y206070D02*
G02X389599Y210900I9822J4831D01*
G01X391800Y206600D02*
G02X390800Y210900I8745J4300D01*
G01X391795Y203888D02*
X390723Y206070D01*
G01X392737Y204695D02*
X391800Y206600D01*
G01X395611Y201217D02*
X391795Y203888D01*
G01X396300Y202200D02*
X392737Y204695D01*
G01X411041Y190413D02*
X395611Y201217D01*
G01X411511Y191549D02*
X396300Y202200D01*
G01X464305Y181022D02*
X411041Y190413D01*
G01X464775Y182158D02*
X411511Y191549D01*
G01X411394Y185355D02*
X461388Y176537D01*
G01X415366Y185873D02*
X461859Y177673D01*
G01X411603Y186537D02*
X415366Y185873D01*
G01X401449Y187108D02*
X411394Y185355D01*
G01X401919Y188244D02*
X411603Y186537D01*
G01X376463Y204602D02*
X401449Y187108D01*
G01X377325Y205464D02*
X401919Y188244D01*
G01X374064Y208030D02*
X376463Y204602D01*
G01X375200Y208500D02*
X377325Y205464D01*
G01X373783Y209627D02*
X374064Y208030D01*
G01X374983Y209732D02*
X375200Y208500D01*
G01X373783Y210992D02*
Y209627D01*
G01X374983Y210993D02*
Y209732D01*
G01X372840Y213440D02*
G02X373783Y210992I-2705J-2448D01*
G01X373563Y214421D02*
G02X374983Y210993I-3428J-3428D01*
G01X372588Y213565D02*
X372840Y213440D01*
G01X373117Y214643D02*
X373563Y214421D01*
G01X373116Y214643D02*
X373117D01*
G01X372578Y213570D02*
X372579D01*
G01X373117Y214643D02*
X373563Y214421D01*
G01X423826Y206363D02*
X436023Y197822D01*
G01X422964Y205501D02*
X435553Y196686D01*
G01X422400Y208400D02*
X423826Y206363D01*
G01X421264Y207930D02*
X422964Y205501D01*
G01X422233Y209348D02*
X422400Y208400D01*
G01X421033Y209243D02*
X421264Y207930D01*
G01X422233Y210981D02*
Y209348D01*
G01X421033Y210980D02*
Y209243D01*
G01X420808Y214421D02*
G02X422233Y210981I-3440J-3440D01*
G01X420085Y213440D02*
G02X421033Y210980I-2717J-2460D01*
G01X420362Y214643D02*
X420808Y214421D01*
G01X419833Y213565D02*
X420085Y213440D01*
G01X419823Y213570D02*
X419824D01*
G01X420361Y214643D02*
X420362D01*
G01X419833Y213565D02*
X420085Y213440D01*
G01X404614Y214644D02*
X404613D01*
G01X404078Y213570D02*
X404343Y213437D01*
G01X405012Y214445D02*
X404614Y214644D01*
G01X404078Y213570D02*
X404343Y213437D01*
G01X404077Y213570D02*
X404078D01*
G01X405212Y214268D02*
G03X405139Y214342I-3881J-3756D01*
G01X404346Y213435D02*
G02X405521Y210523I-3025J-2914D01*
G01X406721D02*
G03X405212Y214268I-5401J0D01*
G01X404346Y213435D02*
G02X405521Y210523I-3025J-2914D01*
G01X406721Y209248D02*
Y210523D01*
G01X405521D02*
Y209142D01*
G01X407086Y207180D02*
X406721Y209248D01*
G01X405521Y209142D02*
X405950Y206710D01*
G01X408387Y205321D02*
X407086Y207180D01*
G01X405950Y206710D02*
X407525Y204459D01*
G01X423681Y194611D02*
X408387Y205321D01*
G01X407525Y204459D02*
X423211Y193475D01*
G01X466063Y187139D02*
X423681Y194611D01*
G01X423211Y193475D02*
X465592Y186003D01*
G01X388867Y214643D02*
X388866D01*
G01X388597Y213436D02*
X388329Y213570D01*
G01X389313Y214421D02*
X388867Y214643D01*
G01X388329Y213570D02*
X388328D01*
G01X388597Y213436D02*
X388329Y213570D01*
G01X389473Y214257D02*
G03X389362Y214372I-3588J-3353D01*
G01X389599Y210900D02*
G03X388597Y213436I-3710J0D01*
G01X390800Y210900D02*
G03X389473Y214257I-4911J0D01*
G01X389599Y210900D02*
G03X388597Y213436I-3710J0D01*
G01X391800Y206600D02*
G02X390800Y210900I8745J4300D01*
G01X390723Y206070D02*
G02X389599Y210900I9822J4831D01*
G01X392737Y204695D02*
X391800Y206600D01*
G01X391795Y203888D02*
X390723Y206070D01*
G01X396300Y202200D02*
X392737Y204695D01*
G01X395611Y201217D02*
X391795Y203888D01*
G01X411511Y191549D02*
X396300Y202200D01*
G01X411041Y190413D02*
X395611Y201217D01*
G01X464775Y182158D02*
X411511Y191549D01*
G01X464305Y181022D02*
X411041Y190413D01*
G01X415366Y185873D02*
X461859Y177673D01*
G01X411394Y185355D02*
X461388Y176537D01*
G01X411603Y186537D02*
X415366Y185873D01*
G01X411394Y185355D02*
X461388Y176537D01*
G01X401919Y188244D02*
X411603Y186537D01*
G01X401449Y187108D02*
X411394Y185355D01*
G01X377325Y205464D02*
X401919Y188244D01*
G01X376463Y204602D02*
X401449Y187108D01*
G01X375200Y208500D02*
X377325Y205464D01*
G01X374064Y208030D02*
X376463Y204602D01*
G01X374983Y209732D02*
X375200Y208500D01*
G01X373783Y209627D02*
X374064Y208030D01*
G01X374983Y210993D02*
Y209732D01*
G01X373783Y210992D02*
Y209627D01*
G01X373563Y214421D02*
G02X374983Y210993I-3428J-3428D01*
G01X372840Y213440D02*
G02X373783Y210992I-2705J-2448D01*
G01X373117Y214643D02*
X373563Y214421D01*
G01X372588Y213565D02*
X372840Y213440D01*
G01X372578Y213570D02*
X372579D01*
G01X373116Y214643D02*
X373117D01*
G01X372588Y213565D02*
X372840Y213440D01*
G01X360045Y205217D02*
X390201Y184102D01*
G01X360993Y206019D02*
X360907Y206079D01*
G01X362121Y205229D02*
X360993Y206019D01*
G01X390671Y185238D02*
X362121Y205229D01*
G01X358441Y207508D02*
X360045Y205217D01*
G01X360907Y206079D02*
X359577Y207978D01*
G01X358074Y209595D02*
X358441Y207508D01*
G01X359577Y207978D02*
X359274Y209700D01*
G01X358074Y210899D02*
Y209595D01*
G01X359274Y209700D02*
Y210900D01*
G01X357844Y212196D02*
G02X358074Y210899I-3548J-1298D01*
G01X359274Y210900D02*
G03X358972Y212608I-4978J1D01*
G01X357344Y213132D02*
G02X357844Y212196I-3049J-2230D01*
G01X358312Y213841D02*
G03X357816Y214420I-4017J-2939D01*
G01X358972Y212608D02*
G03X358312Y213841I-4675J-1709D01*
G01X359274Y210900D02*
G03X358972Y212608I-4978J1D01*
G01X358312Y213841D02*
G03X357816Y214420I-4017J-2939D01*
G01X357344Y213132D02*
G02X357844Y212196I-3049J-2230D01*
G01X358972Y212608D02*
G03X358312Y213841I-4675J-1709D01*
G01X357344Y213132D02*
G02X357844Y212196I-3049J-2230D01*
G01X359274Y210900D02*
G03X358972Y212608I-4978J1D01*
G01X357844Y212196D02*
G02X358074Y210899I-3548J-1298D01*
G01X357344Y213132D02*
G02X357844Y212196I-3049J-2230D01*
G01X359274Y209700D02*
Y210900D01*
G01X358074Y210899D02*
Y209595D01*
G01X359577Y207978D02*
X359274Y209700D01*
G01X358074Y209595D02*
X358441Y207508D01*
G01X360907Y206079D02*
X359577Y207978D01*
G01X358441Y207508D02*
X360045Y205217D01*
G01X360993Y206019D02*
X360907Y206079D01*
G01X360045Y205217D02*
X390201Y184102D01*
G01X362121Y205229D02*
X360993Y206019D01*
G01X360045Y205217D02*
X390201Y184102D01*
G01X390671Y185238D02*
X362121Y205229D01*
G01X360045Y205217D02*
X390201Y184102D01*
G01X383001Y181625D02*
X381016Y181975D01*
G01X377838Y181317D02*
X380807Y180792D01*
G01X381016Y181975D02*
X378308Y182453D01*
G01X381016Y181975D02*
X378308Y182453D01*
G01X377838Y181317D02*
X380807Y180792D01*
G01X383001Y181625D02*
X381016Y181975D01*
G01X428505Y563228D02*
X426536Y565196D01*
G01X442639Y-73346D02*
X538111D01*
G01X440670Y-71378D02*
X442639Y-73346D01*
G01X440670Y-42638D02*
Y-71378D01*
G01X505621Y-55557D02*
X505452Y-56513D01*
G01X506816Y-55691D02*
X506659Y-56582D01*
G01X505817Y-51517D02*
X505621Y-55557D01*
G01X512600Y63500D02*
X506816Y-55691D01*
G01X506029Y-47142D02*
X505957Y-48640D01*
G01X512600Y63500D02*
X506816Y-55691D01*
G01X511394Y63425D02*
X506169Y-44265D01*
G01X512600Y63500D02*
X506816Y-55691D01*
G01X496200Y-55600D02*
X496073Y-57837D01*
G01X497273Y-57984D02*
X497396Y-55700D01*
G01X496429Y-52870D02*
X496200Y-55600D01*
G01X497396Y-55700D02*
X507447Y63968D01*
G01X496796Y-48505D02*
X496670Y-50000D01*
G01X497396Y-55700D02*
X507447Y63968D01*
G01X506242Y63963D02*
X497037Y-45635D01*
G01X497396Y-55700D02*
X507447Y63968D01*
G01X488090Y-46079D02*
X501171Y65287D01*
G01X488116Y-56150D02*
X502384Y65322D01*
G01X487580Y-50429D02*
X487755Y-48939D01*
G01X488116Y-56150D02*
X502384Y65322D01*
G01X486928Y-55976D02*
X487244Y-53289D01*
G01X488116Y-56150D02*
X502384Y65322D01*
G01X486643Y-57595D02*
X486928Y-55976D01*
G01X487825Y-57803D02*
X488116Y-56150D01*
G01X486151Y-58950D02*
G03X486625Y-57803I-1151J1147D01*
G01X487825Y-57837D02*
G03Y-57803I-2825J17D01*
G01X477175Y-57026D02*
Y-58036D01*
G01X478375Y-57131D02*
Y-57862D01*
G01X478213Y-51122D02*
X477175Y-57026D01*
G01X479398Y-51315D02*
X478375Y-57131D01*
G01X478445Y-49640D02*
X478213Y-51122D01*
G01X497565Y64880D02*
X479398Y-51315D01*
G01X479121Y-45313D02*
X478890Y-46795D01*
G01X497565Y64880D02*
X479398Y-51315D01*
G01X496365Y64974D02*
X479566Y-42467D01*
G01X497565Y64880D02*
X479398Y-51315D01*
G01X506816Y-55691D02*
X506659Y-56582D01*
G01X505621Y-55557D02*
X505452Y-56513D01*
G01X512600Y63500D02*
X506816Y-55691D01*
G01X505817Y-51517D02*
X505621Y-55557D01*
G01X506029Y-47142D02*
X505957Y-48640D01*
G01X511394Y63425D02*
X506169Y-44265D01*
G01X497396Y-55700D02*
X507447Y63968D01*
G01X496429Y-52870D02*
X496200Y-55600D01*
G01X496796Y-48505D02*
X496670Y-50000D01*
G01X506242Y63963D02*
X497037Y-45635D01*
G01X497273Y-57984D02*
X497396Y-55700D01*
G01X496200Y-55600D02*
X496073Y-57837D01*
G01X488116Y-56150D02*
X502384Y65322D01*
G01X488090Y-46079D02*
X501171Y65287D01*
G01X487580Y-50429D02*
X487755Y-48939D01*
G01X486928Y-55976D02*
X487244Y-53289D01*
G01X487825Y-57803D02*
X488116Y-56150D01*
G01X486643Y-57595D02*
X486928Y-55976D01*
G01X487825Y-57837D02*
G03Y-57803I-2825J17D01*
G01X486151Y-58950D02*
G03X486625Y-57803I-1151J1147D01*
G01X478375Y-57131D02*
Y-57862D01*
G01X477175Y-57026D02*
Y-58036D01*
G01X479398Y-51315D02*
X478375Y-57131D01*
G01X478213Y-51122D02*
X477175Y-57026D01*
G01X497565Y64880D02*
X479398Y-51315D01*
G01X478445Y-49640D02*
X478213Y-51122D01*
G01X479121Y-45313D02*
X478890Y-46795D01*
G01X496365Y64974D02*
X479566Y-42467D01*
G01X467727Y-58083D02*
G02X467239Y-59261I-1666J0D01*
G01X468927Y-58138D02*
G03Y-58134I-2866J2D01*
G01X467861Y-56305D02*
X467727Y-58083D01*
G01X468927Y-58134D02*
X469057Y-56404D01*
G01X468028Y-54450D02*
X467861Y-56305D01*
G01X469057Y-56404D02*
X469218Y-54619D01*
G01X468600Y-51506D02*
X468028Y-54450D01*
G01X469347Y-53962D02*
X492584Y66037D01*
G01X469255Y-54430D02*
X469347Y-53962D01*
G01X469218Y-54619D02*
X469255Y-54430D01*
G01X468885Y-50033D02*
X468600Y-51506D01*
G01X469347Y-53962D02*
X492584Y66037D01*
G01X469718Y-45733D02*
X469433Y-47206D01*
G01X469347Y-53962D02*
X492584Y66037D01*
G01X470550Y-41433D02*
X470265Y-42906D01*
G01X469347Y-53962D02*
X492584Y66037D01*
G01X491375Y66107D02*
X471098Y-38606D01*
G01X469347Y-53962D02*
X492584Y66037D01*
G01X469347Y-53962D02*
X492584Y66037D01*
G01X468600Y-51506D02*
X468028Y-54450D01*
G01X468885Y-50033D02*
X468600Y-51506D01*
G01X469718Y-45733D02*
X469433Y-47206D01*
G01X470550Y-41433D02*
X470265Y-42906D01*
G01X491375Y66107D02*
X471098Y-38606D01*
G01X469255Y-54430D02*
X469347Y-53962D01*
G01X468600Y-51506D02*
X468028Y-54450D01*
G01X469218Y-54619D02*
X469255Y-54430D01*
G01X468600Y-51506D02*
X468028Y-54450D01*
G01X469057Y-56404D02*
X469218Y-54619D01*
G01X468028Y-54450D02*
X467861Y-56305D01*
G01X468927Y-58134D02*
X469057Y-56404D01*
G01X467861Y-56305D02*
X467727Y-58083D01*
G01X468927Y-58138D02*
G03Y-58134I-2866J2D01*
G01X467727Y-58083D02*
G02X467239Y-59261I-1666J0D01*
G01X458194Y-57072D02*
X458281Y-57730D01*
G01X459472Y-57573D02*
X459406Y-57077D01*
G01X458511Y-54832D02*
X458194Y-57072D01*
G01X459406Y-57077D02*
X459700Y-55000D01*
G01X458518Y-54782D02*
X458511Y-54832D01*
G01X459406Y-57077D02*
X459700Y-55000D01*
G01X458904Y-53094D02*
X458518Y-54782D01*
G01X459700Y-55000D02*
X487318Y65697D01*
G01X459881Y-48825D02*
X459547Y-50287D01*
G01X459700Y-55000D02*
X487318Y65697D01*
G01X486116Y65825D02*
X460524Y-46017D01*
G01X459700Y-55000D02*
X487318Y65697D01*
G01X482041Y65222D02*
X450500Y-54900D01*
G01X452393Y-42962D02*
X480595Y64442D01*
G01X482041Y65222D02*
X450500Y-54900D01*
G01X451947Y-44661D02*
X452393Y-42962D01*
G01X482041Y65222D02*
X450500Y-54900D01*
G01X450835Y-48897D02*
X451216Y-47447D01*
G01X482041Y65222D02*
X450500Y-54900D01*
G01X449339Y-54596D02*
X450104Y-51683D01*
G01X482041Y65222D02*
X450500Y-54900D01*
G01X448786Y-57083D02*
X449339Y-54596D01*
G01X450203Y-56245D02*
X449958Y-57343D01*
G01X450501Y-54900D02*
X450203Y-56245D01*
G01X459700Y-55000D02*
X487318Y65697D01*
G01X458904Y-53094D02*
X458518Y-54782D01*
G01X459881Y-48825D02*
X459547Y-50287D01*
G01X486116Y65825D02*
X460524Y-46017D01*
G01X459406Y-57077D02*
X459700Y-55000D01*
G01X458511Y-54832D02*
X458194Y-57072D01*
G01X458518Y-54782D02*
X458511Y-54832D01*
G01X459472Y-57573D02*
X459406Y-57077D01*
G01X458194Y-57072D02*
X458281Y-57730D01*
G01X450203Y-56245D02*
X449958Y-57343D01*
G01X448786Y-57083D02*
X449339Y-54596D01*
G01X450501Y-54900D02*
X450203Y-56245D01*
G01X448786Y-57083D02*
X449339Y-54596D01*
G01X482041Y65222D02*
X450500Y-54900D01*
G01X452393Y-42962D02*
X480595Y64442D01*
G01X451947Y-44661D02*
X452393Y-42962D01*
G01X450835Y-48897D02*
X451216Y-47447D01*
G01X449339Y-54596D02*
X450104Y-51683D01*
G01X440670Y-42638D02*
G03X439883Y-41850I-787J1D01*
G01X493909Y163846D02*
X511394Y63425D01*
G01X495085Y164093D02*
X512600Y63500D01*
G01X488581Y164053D02*
X506232Y63973D01*
G01X507451D02*
X489717Y164523D01*
G01X501171Y65287D02*
X484424Y160235D01*
G01X502384Y65322D02*
X485560Y160705D01*
G01X496365Y65484D02*
Y64974D01*
G01X497565Y65484D02*
Y64880D01*
G01X497574Y65494D02*
Y65493D01*
G01X479967Y158440D02*
X496355Y65494D01*
G01X481103Y158910D02*
X497574Y65494D01*
G01X495085Y164093D02*
X512600Y63500D01*
G01X493909Y163846D02*
X511394Y63425D01*
G01X507451Y63973D02*
X489717Y164523D01*
G01X488581Y164053D02*
X506232Y63973D01*
G01X502384Y65322D02*
X485560Y160705D01*
G01X501171Y65287D02*
X484424Y160235D01*
G01X497565Y65484D02*
Y64880D01*
G01X496365Y65484D02*
Y64974D01*
G01X497574Y65494D02*
Y65493D01*
G01X496365Y65484D02*
Y64974D01*
G01X481103Y158910D02*
X497574Y65494D01*
G01X479967Y158440D02*
X496355Y65494D01*
G01X475409Y156611D02*
X491365Y66117D01*
G01X492584D02*
X476545Y157081D01*
G01X492584Y66117D02*
X476545Y157081D01*
G01X475409Y156611D02*
X491365Y66117D01*
G01X472523Y145497D02*
X486114Y65956D01*
G01X487313Y66066D02*
X473706Y145699D01*
G01X480900Y67000D02*
X466341Y151912D01*
G01X467479Y152380D02*
X482127Y66949D01*
G01X480911Y66937D02*
X480900Y67000D01*
G01X467479Y152380D02*
X482127Y66949D01*
G01X480847Y65423D02*
X480911Y66937D01*
G01X482112Y66922D02*
X482041Y65221D01*
G01X480595Y64442D02*
X480847Y65401D01*
G01X487313Y66066D02*
X473706Y145699D01*
G01X472523Y145497D02*
X486114Y65956D01*
G01X480595Y64442D02*
X480847Y65401D01*
G01X482112Y66922D02*
X482041Y65221D01*
G01X480847Y65423D02*
X480911Y66937D01*
G01X467479Y152380D02*
X482127Y66949D01*
G01X480900Y67000D02*
X466341Y151912D01*
G01X480911Y66937D02*
X480900Y67000D01*
G01X497478Y170798D02*
X488700Y183334D01*
G01X489562Y184196D02*
X498614Y171268D01*
G01X516311Y63998D02*
X497478Y170798D01*
G01X498614Y171268D02*
X517495Y64195D01*
G01X498614Y171268D02*
X517495Y64195D01*
G01X516311Y63998D02*
X497478Y170798D01*
G01X498614Y171268D02*
X517495Y64195D01*
G01X516311Y63998D02*
X497478Y170798D01*
G01X489562Y184196D02*
X498614Y171268D01*
G01X497478Y170798D02*
X488700Y183334D01*
G01X492952Y167718D02*
X493909Y163846D01*
G01X494064Y168223D02*
X495085Y164093D01*
G01X484657Y179564D02*
X492952Y167718D01*
G01X485519Y180426D02*
X494064Y168223D01*
G01X468498Y190877D02*
X484657Y179564D01*
G01X480538Y175538D02*
X488581Y164053D01*
G01X489717Y164523D02*
X481400Y176400D01*
G01X465593Y186003D02*
X480538Y175538D01*
G01X481400Y176400D02*
X466063Y187139D01*
G01X481400Y176400D02*
X466063Y187139D01*
G01X475221Y173378D02*
X464305Y181022D01*
G01X476083Y174240D02*
X464775Y182158D01*
G01X484424Y160235D02*
X475221Y173378D01*
G01X485560Y160705D02*
X476083Y174240D01*
G01X472978Y168419D02*
X479967Y158440D01*
G01X473840Y169281D02*
X481103Y158910D01*
G01X461388Y176537D02*
X472978Y168419D01*
G01X461858Y177673D02*
X473840Y169281D01*
G01X494064Y168223D02*
X495085Y164093D01*
G01X492952Y167718D02*
X493909Y163846D01*
G01X485519Y180426D02*
X494064Y168223D01*
G01X484657Y179564D02*
X492952Y167718D01*
G01X468498Y190877D02*
X484657Y179564D01*
G01X481400Y176400D02*
X466063Y187139D01*
G01X465593Y186003D02*
X480538Y175538D01*
G01X489717Y164523D02*
X481400Y176400D01*
G01X480538Y175538D02*
X488581Y164053D01*
G01X476083Y174240D02*
X464775Y182158D01*
G01X475221Y173378D02*
X464305Y181022D01*
G01X485560Y160705D02*
X476083Y174240D01*
G01X484424Y160235D02*
X475221Y173378D01*
G01X473840Y169281D02*
X481103Y158910D01*
G01X472978Y168419D02*
X479967Y158440D01*
G01X461858Y177673D02*
X473840Y169281D01*
G01X461388Y176537D02*
X472978Y168419D01*
G01X469781Y164646D02*
X475409Y156611D01*
G01X476545Y157081D02*
X470643Y165508D01*
G01X459431Y171894D02*
X469781Y164646D01*
G01X470643Y165508D02*
X459901Y173030D01*
G01X470643Y165508D02*
X459901Y173030D01*
G01X459431Y171894D02*
X469781Y164646D01*
G01X476545Y157081D02*
X470643Y165508D01*
G01X469781Y164646D02*
X475409Y156611D01*
G01X471000Y154407D02*
X472522Y145497D01*
G01X473043Y149576D02*
X472138Y154875D01*
G01X473706Y145699D02*
X473044Y149576D01*
G01X466965Y160168D02*
X471000Y154407D01*
G01X471096Y156364D02*
X467827Y161030D01*
G01X472138Y154875D02*
X471096Y156364D01*
G01X456599Y167428D02*
X466965Y160168D01*
G01X467827Y161030D02*
X457069Y168564D01*
G01X453905Y167903D02*
X456599Y167428D01*
G01X457069Y168564D02*
X454113Y169085D01*
G01X462610Y157239D02*
X456622Y161432D01*
G01X457092Y162568D02*
X463472Y158101D01*
G01X466341Y151912D02*
X462610Y157239D01*
G01X463472Y158101D02*
X467479Y152380D01*
G01X457069Y168564D02*
X454113Y169085D01*
G01X453905Y167903D02*
X456599Y167428D01*
G01X467827Y161030D02*
X457069Y168564D01*
G01X456599Y167428D02*
X466965Y160168D01*
G01X471096Y156364D02*
X467827Y161030D01*
G01X466965Y160168D02*
X471000Y154407D01*
G01X472138Y154875D02*
X471096Y156364D01*
G01X466965Y160168D02*
X471000Y154407D01*
G01X473043Y149576D02*
X472138Y154875D01*
G01X471000Y154407D02*
X472522Y145497D01*
G01X473706Y145699D02*
X473044Y149576D01*
G01X471000Y154407D02*
X472522Y145497D01*
G01X463472Y158101D02*
X467479Y152380D01*
G01X466341Y151912D02*
X462610Y157239D01*
G01X457092Y162568D02*
X463472Y158101D01*
G01X462610Y157239D02*
X456622Y161432D01*
G01X435831Y133538D02*
X435572Y133668D01*
G01X436109Y134742D02*
X436556Y134518D01*
G01X436108Y134742D02*
X436109D01*
G01X436769Y131104D02*
G03X435831Y133538I-3627J0D01*
G01X436556Y134518D02*
G02X437970Y131104I-3414J-3414D01*
G01X436770Y129612D02*
Y131105D01*
G01X437970Y131104D02*
Y129405D01*
G01X436255Y128162D02*
X436770Y129612D01*
G01X437970Y129405D02*
X437345Y127643D01*
G01X435681Y127222D02*
X436255Y128162D01*
G01X437345Y127643D02*
X436686Y126563D01*
G01X434720Y125855D02*
X435681Y127222D01*
G01X436686Y126563D02*
X435581Y124992D01*
G01X433491Y124995D02*
X434720Y125855D01*
G01X435581Y124992D02*
X435409Y124872D01*
G01X432530Y125164D02*
X433491Y124995D01*
G01X429903Y122482D02*
X431132Y123343D01*
G01X428942Y122652D02*
X429903Y122482D01*
G01X433491Y124995D02*
X434720Y125855D01*
G01X432530Y125164D02*
X433491Y124995D01*
G01X429903Y122482D02*
X431132Y123343D01*
G01X428942Y122652D02*
X429903Y122482D01*
G01X435581Y124992D02*
X435409Y124872D01*
G01X433491Y124995D02*
X434720Y125855D01*
G01X436686Y126563D02*
X435581Y124992D01*
G01X434720Y125855D02*
X435681Y127222D01*
G01X437345Y127643D02*
X436686Y126563D01*
G01X435681Y127222D02*
X436255Y128162D01*
G01X437970Y129405D02*
X437345Y127643D01*
G01X436255Y128162D02*
X436770Y129612D01*
G01X437970Y131104D02*
Y129405D01*
G01X436770Y129612D02*
Y131105D01*
G01X436556Y134518D02*
G02X437970Y131104I-3414J-3414D01*
G01X436769D02*
G03X435831Y133538I-3627J0D01*
G01X436109Y134742D02*
X436556Y134518D01*
G01X435831Y133538D02*
X435572Y133668D01*
G01X436108Y134742D02*
X436109D01*
G01X435831Y133538D02*
X435572Y133668D01*
G01X435573Y213571D02*
X435572D01*
G01X436109Y214646D02*
X436558Y214421D01*
G01X436020Y213347D02*
X435573Y213571D01*
G01X436109Y214646D02*
X436558Y214421D01*
G01X436108Y214645D02*
X436109D01*
G01X436400Y212800D02*
G03X436020Y213347I-691J-74D01*
G01X436558Y214421D02*
G02X437594Y212928I-849J-1695D01*
G01X437300Y208399D02*
G02X436400Y212800I22646J6924D01*
G01X437594Y212928D02*
G03X438448Y208750I22353J2393D01*
G01X437737Y206966D02*
X437300Y208399D01*
G01X438448Y208750D02*
X438829Y207502D01*
G01X438630Y205153D02*
X437747Y206961D01*
G01X438826Y207487D02*
X439573Y205959D01*
G01X441345Y203252D02*
X438630Y205153D01*
G01X439573Y205959D02*
X442034Y204235D01*
G01X445576Y200289D02*
X441345Y203252D01*
G01X442034Y204235D02*
X446046Y201425D01*
G01X470850Y195833D02*
X445576Y200289D01*
G01X446046Y201425D02*
X471320Y196969D01*
G01X488700Y183334D02*
X470850Y195833D01*
G01X471320Y196969D02*
X489562Y184196D01*
G01X471320Y196969D02*
X489562Y184196D01*
G01X488700Y183334D02*
X470850Y195833D01*
G01X446046Y201425D02*
X471320Y196969D01*
G01X470850Y195833D02*
X445576Y200289D01*
G01X442034Y204235D02*
X446046Y201425D01*
G01X445576Y200289D02*
X441345Y203252D01*
G01X439573Y205959D02*
X442034Y204235D01*
G01X441345Y203252D02*
X438630Y205153D01*
G01X438826Y207487D02*
X439573Y205959D01*
G01X438630Y205153D02*
X437747Y206961D01*
G01X438448Y208750D02*
X438829Y207502D01*
G01X437737Y206966D02*
X437300Y208399D01*
G01X437594Y212928D02*
G03X438448Y208750I22353J2393D01*
G01X437300Y208399D02*
G02X436400Y212800I22646J6924D01*
G01X436558Y214421D02*
G02X437594Y212928I-849J-1695D01*
G01X436400Y212800D02*
G03X436020Y213347I-691J-74D01*
G01X436109Y214646D02*
X436558Y214421D01*
G01X435573Y213571D02*
X435572D01*
G01X436020Y213347D02*
X435573Y213571D01*
G01X436108Y214645D02*
X436109D01*
G01X436020Y213347D02*
X435573Y213571D01*
G01X468968Y192013D02*
X485519Y180426D01*
G01X455792Y193118D02*
X468498Y190877D01*
G01X456000Y194300D02*
X468968Y192013D01*
G01X435553Y196686D02*
X455792Y193118D01*
G01X436023Y197822D02*
X456000Y194300D01*
G01X465592Y186003D02*
X465593D01*
G01X468968Y192013D02*
X485519Y180426D01*
G01X456000Y194300D02*
X468968Y192013D01*
G01X455792Y193118D02*
X468498Y190877D01*
G01X436023Y197822D02*
X456000Y194300D01*
G01X435553Y196686D02*
X455792Y193118D01*
G01X465592Y186003D02*
X465593D01*
G01X465592D02*
X465593D01*
G01X428504Y544723D02*
Y563227D01*
G01Y544723D02*
G03X437953I4724J0D01*
G01Y563227D02*
Y544723D01*
G01X428505Y544724D02*
Y563228D01*
G01Y544724D02*
G03X437954I4725J0D01*
G01Y563228D02*
Y544724D01*
G01X439922Y565196D02*
X437954Y563228D01*
G01X540828Y565196D02*
X439922D01*
G01X547954Y-73346D02*
X622403D01*
G01X547954D02*
Y-7874D01*
G01X540080Y-71378D02*
Y-3937D01*
G01X538111Y-73346D02*
X540080Y-71378D01*
G01X515826Y11172D02*
X516381Y61302D01*
G01X517608Y63586D02*
X516300Y-54413D01*
G01X515213Y-44193D02*
X515826Y11172D01*
G01X517608Y63586D02*
X516300Y-54413D01*
G01X514971Y-57940D02*
X515100Y-54400D01*
G01X516272Y-55214D02*
X516171Y-57965D01*
G01X514483Y-59117D02*
G03X514971Y-57940I-1178J1178D01*
G01X516171Y-57965D02*
G02Y-57982I-2866J-9D01*
G01Y-57965D02*
G02Y-57982I-2866J-9D01*
G01X514483Y-59117D02*
G03X514971Y-57940I-1178J1178D01*
G01X516272Y-55214D02*
X516171Y-57965D01*
G01X514971Y-57940D02*
X515100Y-54400D01*
G01X517608Y63586D02*
X516300Y-54413D01*
G01X515826Y11172D02*
X516381Y61302D01*
G01X515213Y-44193D02*
X515826Y11172D01*
G01X558662Y9505D02*
Y155374D01*
G01X557509Y6721D02*
G03X558662Y9505I-2784J2784D01*
G01X551942Y1153D02*
X557509Y6721D01*
G01X549158Y0D02*
G03X551942Y1153I0J3937D01*
G01X544017Y0D02*
X549158D01*
G01X544017D02*
G03X540080Y-3937I0J-3937D01*
G01X547954Y-7874D02*
X549158D01*
G01Y0D02*
G03X551942Y1153I0J3937D01*
G01X549158Y-7875D02*
G03X557510Y-4415I0J11811D01*
G01X551942Y1153D02*
X557509Y6721D01*
G01X557510Y-4414D02*
X563077Y1154D01*
G01X557509Y6721D02*
G03X558662Y9505I-2784J2784D01*
G01X563077Y1153D02*
G03X566536Y9507I-8352J8351D01*
G01X558662Y9505D02*
Y155374D01*
G01X566536Y9505D02*
Y18655D01*
G01D02*
G03X558662I-3937J-1D01*
G01X517501Y64188D02*
X517608Y63586D01*
G01X516406Y63486D02*
X516318Y63979D01*
G01X517501Y64188D02*
X517608Y63586D01*
G01X517501Y64188D02*
X517608Y63586D01*
G01X516406Y63486D02*
X516318Y63979D01*
G01X516406Y63486D02*
X516318Y63979D01*
G01X558662Y49363D02*
G03X566536I3937J0D01*
G01D02*
Y151437D01*
G01X562599Y159311D02*
X611812D01*
G01X562599D02*
G03X558662Y155374I0J-3937D01*
G01X562599Y159311D02*
G03X558662Y155374I0J-3937D01*
G01X562599Y159311D02*
X611812D01*
G01X566536Y151437D02*
X574076D01*
G01D02*
G03Y159311I0J3937D01*
G01X564353Y249862D02*
G03Y241988I0J-3937D01*
G01X521844D02*
G03Y249862I0J3937D01*
G01X542796Y495787D02*
Y563228D01*
G01Y495787D02*
G03X546733Y491850I3937J0D01*
G01X606244D02*
X546733D01*
G01X606244D02*
X546733D01*
G01X542796Y495787D02*
G03X546733Y491850I3937J0D01*
G01X550670Y499724D02*
Y563622D01*
G01X570124Y491850D02*
G03Y499724I0J3937D01*
G01D02*
X550670D01*
G01Y565196D02*
X622403D01*
G01X542796Y563228D02*
X540828Y565196D01*
G01X550670Y563622D02*
Y565196D01*
G01X622403Y-73346D02*
G03X637403Y-58346I0J15000D01*
G01Y253799D02*
Y-58346D01*
G01X615749Y163248D02*
Y228546D01*
G01X611812Y159311D02*
G03X615749Y163248I0J3937D01*
G01X611812Y159311D02*
G03X615749Y163248I0J3937D01*
G01X611812Y151437D02*
G03X623623Y163248I0J11811D01*
G01X615749D02*
Y228546D01*
G01X623623Y163248D02*
Y228546D01*
G01X604785Y159311D02*
G03Y151437I0J-3937D01*
G01D02*
X611812D01*
G01X615749Y253799D02*
Y482345D01*
G01X611812Y249862D02*
G03X615749Y253799I0J3937D01*
G01X605091Y240835D02*
G03X602307Y241988I-2784J-2784D01*
G01X614596Y231330D02*
X605091Y240835D01*
G01X615749Y228546D02*
G03X614596Y231330I-3937J0D01*
G01X615749Y228546D02*
G03X614596Y231330I-3937J0D01*
G01D02*
X605091Y240835D01*
G01D02*
G03X602307Y241988I-2784J-2784D01*
G01X611812Y249862D02*
G03X615749Y253799I0J3937D01*
G01D02*
Y482345D01*
G01X623623Y253799D02*
Y274659D01*
G01X637403Y253799D02*
Y482345D01*
G01X623623Y228546D02*
Y253799D01*
G01Y274659D02*
G03X615749I-3937J0D01*
G01Y305368D02*
G03X623623I3937J0D01*
G01D02*
Y410289D01*
G01D02*
G03X615749I-3937J0D01*
G01X609028Y490697D02*
G03X606244Y491850I-2784J-2784D01*
G01X614596Y485129D02*
X609028Y490697D01*
G01X615749Y482345D02*
G03X614596Y485129I-3937J0D01*
G01X615749Y482345D02*
G03X614596Y485129I-3937J0D01*
G01X623623Y482345D02*
G03X620164Y490697I-11811J1D01*
G01X614596Y485129D02*
X609028Y490697D01*
G01X620164D02*
X614596Y496265D01*
G01X609028Y490697D02*
G03X606244Y491850I-2784J-2784D01*
G01X614596Y496265D02*
G03X606244Y499724I-8351J-8352D01*
G01D02*
X600833D01*
G01X637403Y482345D02*
Y550196D01*
G01X600833Y499724D02*
G03Y491850I0J-3937D01*
G01X615749Y440998D02*
G03X623623I3937J0D01*
G01D02*
Y482345D01*
G01X637403Y550196D02*
G03X622403Y565196I-15000J0D01*
G54D12*
G01X-15353Y-106096D02*
Y-123596D01*
G01X-20375Y-106096D02*
X-10331D01*
G01X-1565Y-123596D02*
Y-106096D01*
G01Y-114554D02*
X-473Y-113096D01*
X619Y-112221D01*
X2365Y-111930D01*
X3675Y-112221D01*
X5204Y-113388D01*
X5859Y-115138D01*
Y-123596D01*
G01X19647Y-111930D02*
Y-123596D01*
G01Y-107263D02*
X19210Y-106971D01*
Y-106388D01*
X19647Y-106096D01*
X20084Y-106388D01*
Y-106971D01*
X19647Y-107263D01*
G01X33872Y-121555D02*
X34964Y-122721D01*
X36492Y-123596D01*
X37802D01*
X39112Y-123013D01*
X39985Y-122138D01*
X40422Y-120972D01*
X40204Y-119221D01*
X39330Y-118346D01*
X35400Y-116596D01*
X34527Y-114554D01*
X34964Y-113096D01*
X35837Y-112221D01*
X37147Y-111930D01*
X38457Y-112221D01*
X39767Y-113096D01*
G01X69090Y-127971D02*
X70619Y-129138D01*
X72365Y-129429D01*
X73893Y-129138D01*
X75204Y-127680D01*
X76077Y-125638D01*
Y-111930D01*
G01Y-114263D02*
X75204Y-113096D01*
X73893Y-112221D01*
X72365Y-111930D01*
X70619Y-112513D01*
X69527Y-113679D01*
X68653Y-115721D01*
X68217Y-117763D01*
X68435Y-119513D01*
X69309Y-121555D01*
X70619Y-123013D01*
X72365Y-123596D01*
X73675Y-123304D01*
X75204Y-122138D01*
X76077Y-120972D01*
G01X86372Y-115721D02*
X93359D01*
X92704Y-113679D01*
X91612Y-112513D01*
X90084Y-111930D01*
X88555Y-112221D01*
X87245Y-113096D01*
X86372Y-115138D01*
X85935Y-116888D01*
Y-118638D01*
X86372Y-120388D01*
X87464Y-122138D01*
X88774Y-123304D01*
X90302Y-123596D01*
X91830Y-123013D01*
X93359Y-121263D01*
G01X104090Y-123596D02*
Y-111930D01*
G01Y-114263D02*
X105182Y-113096D01*
X106274Y-112221D01*
X107802Y-111930D01*
X108893Y-112221D01*
X110204Y-113096D01*
G01X120717Y-123596D02*
Y-106096D01*
G01Y-114846D02*
X121809Y-113096D01*
X123119Y-112221D01*
X124429Y-111930D01*
X126393Y-112513D01*
X127704Y-113679D01*
X128577Y-115721D01*
Y-118054D01*
X128140Y-120388D01*
X127267Y-122138D01*
X125739Y-123304D01*
X124429Y-123596D01*
X123119Y-123304D01*
X121809Y-122430D01*
X120717Y-120972D01*
G01X138872Y-115721D02*
X145859D01*
X145204Y-113679D01*
X144112Y-112513D01*
X142584Y-111930D01*
X141055Y-112221D01*
X139745Y-113096D01*
X138872Y-115138D01*
X138435Y-116888D01*
Y-118638D01*
X138872Y-120388D01*
X139964Y-122138D01*
X141274Y-123304D01*
X142802Y-123596D01*
X144330Y-123013D01*
X145859Y-121263D01*
G01X156590Y-123596D02*
Y-111930D01*
G01Y-114263D02*
X157682Y-113096D01*
X158774Y-112221D01*
X160302Y-111930D01*
X161393Y-112221D01*
X162704Y-113096D01*
G01X194647Y-111930D02*
Y-123596D01*
G01Y-107263D02*
X194210Y-106971D01*
Y-106388D01*
X194647Y-106096D01*
X195084Y-106388D01*
Y-106971D01*
X194647Y-107263D01*
G01X208872Y-121555D02*
X209964Y-122721D01*
X211492Y-123596D01*
X212802D01*
X214112Y-123013D01*
X214985Y-122138D01*
X215422Y-120972D01*
X215204Y-119221D01*
X214330Y-118346D01*
X210400Y-116596D01*
X209527Y-114554D01*
X209964Y-113096D01*
X210837Y-112221D01*
X212147Y-111930D01*
X213457Y-112221D01*
X214767Y-113096D01*
G01X243653Y-127971D02*
X245182Y-129138D01*
X246492Y-129429D01*
X248239Y-128846D01*
X249549Y-127388D01*
X250204Y-124762D01*
Y-111930D01*
G01Y-107263D02*
X249767Y-106971D01*
Y-106388D01*
X250204Y-106096D01*
X250640Y-106388D01*
Y-106971D01*
X250204Y-107263D01*
G01X260935Y-111930D02*
Y-120096D01*
X261809Y-122138D01*
X263119Y-123304D01*
X264647Y-123596D01*
X266175Y-123304D01*
X267485Y-122138D01*
X268359Y-120096D01*
G01Y-123596D02*
Y-111930D01*
G01X278872Y-121555D02*
X279964Y-122721D01*
X281492Y-123596D01*
X282802D01*
X284112Y-123013D01*
X284985Y-122138D01*
X285422Y-120972D01*
X285204Y-119221D01*
X284330Y-118346D01*
X280400Y-116596D01*
X279527Y-114554D01*
X279964Y-113096D01*
X280837Y-112221D01*
X282147Y-111930D01*
X283457Y-112221D01*
X284767Y-113096D01*
G01X299647Y-106096D02*
Y-123596D01*
G01X296590Y-111930D02*
X302704D01*
G01X333337Y-123596D02*
Y-108721D01*
X333774Y-107263D01*
X334647Y-106388D01*
X335957Y-106096D01*
X337267Y-106679D01*
X337922Y-108138D01*
G01X335302Y-113096D02*
X330935D01*
G01X352147Y-123596D02*
X350837Y-123304D01*
X349527Y-122138D01*
X348653Y-120096D01*
X348217Y-117763D01*
X348653Y-115429D01*
X349527Y-113388D01*
X350837Y-112221D01*
X352147Y-111930D01*
X353457Y-112221D01*
X354767Y-113388D01*
X355640Y-115429D01*
X355859Y-117763D01*
X355640Y-120096D01*
X354767Y-122138D01*
X353457Y-123304D01*
X352147Y-123596D01*
G01X366590D02*
Y-111930D01*
G01Y-114263D02*
X367682Y-113096D01*
X368774Y-112221D01*
X370302Y-111930D01*
X371393Y-112221D01*
X372704Y-113096D01*
G01X400062Y-128846D02*
X401372Y-129429D01*
X403119Y-128846D01*
X404210Y-127680D01*
X405084Y-126221D01*
X406393Y-121555D01*
X409232Y-111930D01*
G01X402245D02*
X406393Y-121555D01*
G01X422147Y-123596D02*
X420837Y-123304D01*
X419527Y-122138D01*
X418653Y-120096D01*
X418217Y-117763D01*
X418653Y-115429D01*
X419527Y-113388D01*
X420837Y-112221D01*
X422147Y-111930D01*
X423457Y-112221D01*
X424767Y-113388D01*
X425640Y-115429D01*
X425859Y-117763D01*
X425640Y-120096D01*
X424767Y-122138D01*
X423457Y-123304D01*
X422147Y-123596D01*
G01X435935Y-111930D02*
Y-120096D01*
X436809Y-122138D01*
X438119Y-123304D01*
X439647Y-123596D01*
X441175Y-123304D01*
X442485Y-122138D01*
X443359Y-120096D01*
G01Y-123596D02*
Y-111930D01*
G01X454090Y-123596D02*
Y-111930D01*
G01Y-114263D02*
X455182Y-113096D01*
X456274Y-112221D01*
X457802Y-111930D01*
X458893Y-112221D01*
X460204Y-113096D01*
G01X489090Y-123596D02*
Y-111930D01*
G01Y-114263D02*
X490182Y-113096D01*
X491274Y-112221D01*
X492802Y-111930D01*
X493893Y-112221D01*
X495204Y-113096D01*
G01X506372Y-115721D02*
X513359D01*
X512704Y-113679D01*
X511612Y-112513D01*
X510084Y-111930D01*
X508555Y-112221D01*
X507245Y-113096D01*
X506372Y-115138D01*
X505935Y-116888D01*
Y-118638D01*
X506372Y-120388D01*
X507464Y-122138D01*
X508774Y-123304D01*
X510302Y-123596D01*
X511830Y-123013D01*
X513359Y-121263D01*
G01X525837Y-123596D02*
Y-108721D01*
X526274Y-107263D01*
X527147Y-106388D01*
X528457Y-106096D01*
X529767Y-106679D01*
X530422Y-108138D01*
G01X527802Y-113096D02*
X523435D01*
G01X541372Y-115721D02*
X548359D01*
X547704Y-113679D01*
X546612Y-112513D01*
X545084Y-111930D01*
X543555Y-112221D01*
X542245Y-113096D01*
X541372Y-115138D01*
X540935Y-116888D01*
Y-118638D01*
X541372Y-120388D01*
X542464Y-122138D01*
X543774Y-123304D01*
X545302Y-123596D01*
X546830Y-123013D01*
X548359Y-121263D01*
G01X559090Y-123596D02*
Y-111930D01*
G01Y-114263D02*
X560182Y-113096D01*
X561274Y-112221D01*
X562802Y-111930D01*
X563893Y-112221D01*
X565204Y-113096D01*
G01X576372Y-115721D02*
X583359D01*
X582704Y-113679D01*
X581612Y-112513D01*
X580084Y-111930D01*
X578555Y-112221D01*
X577245Y-113096D01*
X576372Y-115138D01*
X575935Y-116888D01*
Y-118638D01*
X576372Y-120388D01*
X577464Y-122138D01*
X578774Y-123304D01*
X580302Y-123596D01*
X581830Y-123013D01*
X583359Y-121263D01*
G01X593435Y-123596D02*
Y-111930D01*
G01Y-114846D02*
X594309Y-113388D01*
X595619Y-112221D01*
X597365Y-111930D01*
X598893Y-112221D01*
X600204Y-113388D01*
X600859Y-115429D01*
Y-123596D01*
G01X618140Y-113388D02*
X616612Y-112221D01*
X615302Y-111930D01*
X613555Y-112513D01*
X612245Y-113679D01*
X611372Y-115721D01*
X611153Y-117763D01*
X611372Y-119805D01*
X612245Y-121555D01*
X613555Y-123013D01*
X615302Y-123596D01*
X616830Y-123013D01*
X618140Y-121846D01*
G01X628872Y-115721D02*
X635859D01*
X635204Y-113679D01*
X634112Y-112513D01*
X632584Y-111930D01*
X631055Y-112221D01*
X629745Y-113096D01*
X628872Y-115138D01*
X628435Y-116888D01*
Y-118638D01*
X628872Y-120388D01*
X629964Y-122138D01*
X631274Y-123304D01*
X632802Y-123596D01*
X634330Y-123013D01*
X635859Y-121263D01*
G01X667147Y-106096D02*
Y-123596D01*
G01X664090Y-111930D02*
X670204D01*
G01X684647Y-123596D02*
X683337Y-123304D01*
X682027Y-122138D01*
X681153Y-120096D01*
X680717Y-117763D01*
X681153Y-115429D01*
X682027Y-113388D01*
X683337Y-112221D01*
X684647Y-111930D01*
X685957Y-112221D01*
X687267Y-113388D01*
X688140Y-115429D01*
X688359Y-117763D01*
X688140Y-120096D01*
X687267Y-122138D01*
X685957Y-123304D01*
X684647Y-123596D01*
G01X718337D02*
Y-108721D01*
X718774Y-107263D01*
X719647Y-106388D01*
X720957Y-106096D01*
X722267Y-106679D01*
X722922Y-108138D01*
G01X720302Y-113096D02*
X715935D01*
G01X737147Y-111930D02*
Y-123596D01*
G01Y-107263D02*
X736710Y-106971D01*
Y-106388D01*
X737147Y-106096D01*
X737584Y-106388D01*
Y-106971D01*
X737147Y-107263D01*
G01X750935Y-123596D02*
Y-111930D01*
G01Y-114846D02*
X751809Y-113388D01*
X753119Y-112221D01*
X754865Y-111930D01*
X756393Y-112221D01*
X757704Y-113388D01*
X758359Y-115429D01*
Y-123596D01*
G01X776077Y-106096D02*
Y-123596D01*
G01Y-120972D02*
X775204Y-122430D01*
X773893Y-123304D01*
X772365Y-123596D01*
X770619Y-123013D01*
X769309Y-121555D01*
X768435Y-119805D01*
X768217Y-117763D01*
X768435Y-115721D01*
X769309Y-113971D01*
X770619Y-112513D01*
X772365Y-111930D01*
X773893Y-112221D01*
X774985Y-112805D01*
X776077Y-113971D01*
G01X807147Y-106096D02*
Y-123596D01*
G01X804090Y-111930D02*
X810204D01*
G01X820935Y-123596D02*
Y-106096D01*
G01Y-114554D02*
X822027Y-113096D01*
X823119Y-112221D01*
X824865Y-111930D01*
X826175Y-112221D01*
X827704Y-113388D01*
X828359Y-115138D01*
Y-123596D01*
G01X838872Y-115721D02*
X845859D01*
X845204Y-113679D01*
X844112Y-112513D01*
X842584Y-111930D01*
X841055Y-112221D01*
X839745Y-113096D01*
X838872Y-115138D01*
X838435Y-116888D01*
Y-118638D01*
X838872Y-120388D01*
X839964Y-122138D01*
X841274Y-123304D01*
X842802Y-123596D01*
X844330Y-123013D01*
X845859Y-121263D01*
G01X872344Y-123596D02*
Y-106096D01*
X876710D01*
X878457Y-106971D01*
X879767Y-108138D01*
X880859Y-109887D01*
X881732Y-111930D01*
X881950Y-114846D01*
X881732Y-117763D01*
X880859Y-119805D01*
X879767Y-121555D01*
X878457Y-122721D01*
X876710Y-123596D01*
X872344D01*
G01X890280D02*
Y-106096D01*
X895520D01*
X897267Y-106971D01*
X898577Y-109013D01*
X899014Y-111346D01*
X898577Y-113679D01*
X897485Y-115429D01*
X895520Y-116305D01*
X890280D01*
G01X929647Y-111930D02*
Y-123596D01*
G01Y-107263D02*
X929210Y-106971D01*
Y-106388D01*
X929647Y-106096D01*
X930084Y-106388D01*
Y-106971D01*
X929647Y-107263D01*
G01X940597Y-123596D02*
Y-111930D01*
G01Y-115138D02*
X941252Y-113679D01*
X942344Y-112513D01*
X943872Y-111930D01*
X945400Y-112513D01*
X946492Y-113679D01*
X947147Y-115138D01*
Y-123596D01*
G01Y-115138D02*
X947802Y-113679D01*
X948893Y-112513D01*
X950422Y-111930D01*
X951950Y-112513D01*
X953042Y-113679D01*
X953697Y-115429D01*
Y-123596D01*
G01X960717Y-129429D02*
Y-111930D01*
G01Y-114554D02*
X961809Y-113096D01*
X962900Y-112221D01*
X964647Y-111930D01*
X966175Y-112221D01*
X967704Y-113679D01*
X968359Y-115721D01*
X968577Y-117763D01*
X968359Y-119805D01*
X967704Y-121846D01*
X966393Y-123013D01*
X964647Y-123596D01*
X963119Y-123304D01*
X961590Y-122430D01*
X960717Y-121263D01*
G01X978872Y-115721D02*
X985859D01*
X985204Y-113679D01*
X984112Y-112513D01*
X982584Y-111930D01*
X981055Y-112221D01*
X979745Y-113096D01*
X978872Y-115138D01*
X978435Y-116888D01*
Y-118638D01*
X978872Y-120388D01*
X979964Y-122138D01*
X981274Y-123304D01*
X982802Y-123596D01*
X984330Y-123013D01*
X985859Y-121263D01*
G01X1003577Y-106096D02*
Y-123596D01*
G01Y-120972D02*
X1002704Y-122430D01*
X1001393Y-123304D01*
X999865Y-123596D01*
X998119Y-123013D01*
X996809Y-121555D01*
X995935Y-119805D01*
X995717Y-117763D01*
X995935Y-115721D01*
X996809Y-113971D01*
X998119Y-112513D01*
X999865Y-111930D01*
X1001393Y-112221D01*
X1002485Y-112805D01*
X1003577Y-113971D01*
G01X1021077Y-123596D02*
Y-111930D01*
G01Y-113971D02*
X1020204Y-112805D01*
X1018893Y-112221D01*
X1017365Y-111930D01*
X1015837Y-112513D01*
X1014527Y-113679D01*
X1013653Y-115429D01*
X1013217Y-117763D01*
X1013653Y-120096D01*
X1014527Y-121846D01*
X1015837Y-123013D01*
X1017365Y-123596D01*
X1018893Y-123304D01*
X1020204Y-122430D01*
X1021077Y-121263D01*
G01X1030935Y-123596D02*
Y-111930D01*
G01Y-114846D02*
X1031809Y-113388D01*
X1033119Y-112221D01*
X1034865Y-111930D01*
X1036393Y-112221D01*
X1037704Y-113388D01*
X1038359Y-115429D01*
Y-123596D01*
G01X1055640Y-113388D02*
X1054112Y-112221D01*
X1052802Y-111930D01*
X1051055Y-112513D01*
X1049745Y-113679D01*
X1048872Y-115721D01*
X1048653Y-117763D01*
X1048872Y-119805D01*
X1049745Y-121555D01*
X1051055Y-123013D01*
X1052802Y-123596D01*
X1054330Y-123013D01*
X1055640Y-121846D01*
G01X1066372Y-115721D02*
X1073359D01*
X1072704Y-113679D01*
X1071612Y-112513D01*
X1070084Y-111930D01*
X1068555Y-112221D01*
X1067245Y-113096D01*
X1066372Y-115138D01*
X1065935Y-116888D01*
Y-118638D01*
X1066372Y-120388D01*
X1067464Y-122138D01*
X1068774Y-123304D01*
X1070302Y-123596D01*
X1071830Y-123013D01*
X1073359Y-121263D01*
G01X1104647Y-106096D02*
Y-123596D01*
G01X1101590Y-111930D02*
X1107704D01*
G01X1119090Y-123596D02*
Y-111930D01*
G01Y-114263D02*
X1120182Y-113096D01*
X1121274Y-112221D01*
X1122802Y-111930D01*
X1123893Y-112221D01*
X1125204Y-113096D01*
G01X1143577Y-123596D02*
Y-111930D01*
G01Y-113971D02*
X1142704Y-112805D01*
X1141393Y-112221D01*
X1139865Y-111930D01*
X1138337Y-112513D01*
X1137027Y-113679D01*
X1136153Y-115429D01*
X1135717Y-117763D01*
X1136153Y-120096D01*
X1137027Y-121846D01*
X1138337Y-123013D01*
X1139865Y-123596D01*
X1141393Y-123304D01*
X1142704Y-122430D01*
X1143577Y-121263D01*
G01X1160640Y-113388D02*
X1159112Y-112221D01*
X1157802Y-111930D01*
X1156055Y-112513D01*
X1154745Y-113679D01*
X1153872Y-115721D01*
X1153653Y-117763D01*
X1153872Y-119805D01*
X1154745Y-121555D01*
X1156055Y-123013D01*
X1157802Y-123596D01*
X1159330Y-123013D01*
X1160640Y-121846D01*
G01X1171372Y-115721D02*
X1178359D01*
X1177704Y-113679D01*
X1176612Y-112513D01*
X1175084Y-111930D01*
X1173555Y-112221D01*
X1172245Y-113096D01*
X1171372Y-115138D01*
X1170935Y-116888D01*
Y-118638D01*
X1171372Y-120388D01*
X1172464Y-122138D01*
X1173774Y-123304D01*
X1175302Y-123596D01*
X1176830Y-123013D01*
X1178359Y-121263D01*
G01X1188872Y-121555D02*
X1189964Y-122721D01*
X1191492Y-123596D01*
X1192802D01*
X1194112Y-123013D01*
X1194985Y-122138D01*
X1195422Y-120972D01*
X1195204Y-119221D01*
X1194330Y-118346D01*
X1190400Y-116596D01*
X1189527Y-114554D01*
X1189964Y-113096D01*
X1190837Y-112221D01*
X1192147Y-111930D01*
X1193457Y-112221D01*
X1194767Y-113096D01*
G01X1227147Y-111930D02*
Y-123596D01*
G01Y-107263D02*
X1226710Y-106971D01*
Y-106388D01*
X1227147Y-106096D01*
X1227584Y-106388D01*
Y-106971D01*
X1227147Y-107263D01*
G01X1240935Y-123596D02*
Y-111930D01*
G01Y-114846D02*
X1241809Y-113388D01*
X1243119Y-112221D01*
X1244865Y-111930D01*
X1246393Y-112221D01*
X1247704Y-113388D01*
X1248359Y-115429D01*
Y-123596D01*
G01X1279647D02*
Y-106096D01*
G01X1301077Y-123596D02*
Y-111930D01*
G01Y-113971D02*
X1300204Y-112805D01*
X1298893Y-112221D01*
X1297365Y-111930D01*
X1295837Y-112513D01*
X1294527Y-113679D01*
X1293653Y-115429D01*
X1293217Y-117763D01*
X1293653Y-120096D01*
X1294527Y-121846D01*
X1295837Y-123013D01*
X1297365Y-123596D01*
X1298893Y-123304D01*
X1300204Y-122430D01*
X1301077Y-121263D01*
G01X1310062Y-128846D02*
X1311372Y-129429D01*
X1313119Y-128846D01*
X1314210Y-127680D01*
X1315084Y-126221D01*
X1316393Y-121555D01*
X1319232Y-111930D01*
G01X1312245D02*
X1316393Y-121555D01*
G01X1328872Y-115721D02*
X1335859D01*
X1335204Y-113679D01*
X1334112Y-112513D01*
X1332584Y-111930D01*
X1331055Y-112221D01*
X1329745Y-113096D01*
X1328872Y-115138D01*
X1328435Y-116888D01*
Y-118638D01*
X1328872Y-120388D01*
X1329964Y-122138D01*
X1331274Y-123304D01*
X1332802Y-123596D01*
X1334330Y-123013D01*
X1335859Y-121263D01*
G01X1346590Y-123596D02*
Y-111930D01*
G01Y-114263D02*
X1347682Y-113096D01*
X1348774Y-112221D01*
X1350302Y-111930D01*
X1351393Y-112221D01*
X1352704Y-113096D01*
G01X1380280Y-106096D02*
Y-123596D01*
X1389014D01*
G01X1402147D02*
Y-106096D01*
X1399527Y-109596D01*
G01Y-123596D02*
X1404767D01*
G01X1419647Y-124179D02*
X1419210Y-123888D01*
Y-123304D01*
X1419647Y-123013D01*
X1420084Y-123304D01*
Y-123888D01*
X1419647Y-124179D01*
G01X748903Y471246D02*
X750431Y471538D01*
X752178Y472412D01*
X753270Y473870D01*
X753706Y475913D01*
X753270Y477954D01*
X751960Y479704D01*
X749995Y480579D01*
X747811D01*
X746501Y481163D01*
X745409Y482621D01*
X744973Y484662D01*
X745628Y486704D01*
X747156Y488163D01*
X748903Y488746D01*
X750649Y488163D01*
X752178Y486704D01*
X752833Y484662D01*
X752396Y482621D01*
X751305Y481163D01*
X749995Y480579D01*
X747811D01*
X745846Y479704D01*
X744536Y477954D01*
X744100Y475913D01*
X744536Y473870D01*
X745628Y472412D01*
X747375Y471538D01*
X748903Y471246D01*
G01X761600Y473870D02*
X762909Y472412D01*
X764438Y471538D01*
X766403Y471246D01*
X768368Y471829D01*
X769896Y472996D01*
X770988Y475037D01*
X771206Y477371D01*
X770770Y479704D01*
X769678Y481163D01*
X768149Y482329D01*
X766621Y482621D01*
X765093Y482329D01*
X763128Y481163D01*
X763783Y488746D01*
X769678D01*
G01X783903Y470663D02*
X783466Y470954D01*
Y471538D01*
X783903Y471829D01*
X784340Y471538D01*
Y470954D01*
X783903Y470663D01*
G01X801403Y488746D02*
X799656Y488163D01*
X798346Y486704D01*
X797473Y484955D01*
X796818Y482621D01*
X796600Y479996D01*
X796818Y477371D01*
X797473Y475037D01*
X798346Y473287D01*
X799656Y471829D01*
X801403Y471246D01*
X803149Y471829D01*
X804460Y473287D01*
X805333Y475037D01*
X805988Y477371D01*
X806206Y479996D01*
X805988Y482621D01*
X805333Y484955D01*
X804460Y486704D01*
X803149Y488163D01*
X801403Y488746D01*
G01X745191Y438637D02*
X746720Y437179D01*
X748466Y436596D01*
X750213Y437179D01*
X751741Y438929D01*
X752833Y441554D01*
X753270Y444179D01*
Y447387D01*
X752833Y450012D01*
X751741Y452346D01*
X750431Y453513D01*
X748903Y454096D01*
X747156Y453513D01*
X745846Y452346D01*
X744973Y450596D01*
X744536Y448262D01*
X744973Y446221D01*
X746065Y444179D01*
X747375Y443012D01*
X748903Y442721D01*
X750649Y443304D01*
X751960Y444763D01*
X753270Y447387D01*
G01X766403Y454096D02*
X764656Y453513D01*
X763346Y452054D01*
X762473Y450305D01*
X761818Y447971D01*
X761600Y445346D01*
X761818Y442721D01*
X762473Y440387D01*
X763346Y438637D01*
X764656Y437179D01*
X766403Y436596D01*
X768149Y437179D01*
X769460Y438637D01*
X770333Y440387D01*
X770988Y442721D01*
X771206Y445346D01*
X770988Y447971D01*
X770333Y450305D01*
X769460Y452054D01*
X768149Y453513D01*
X766403Y454096D01*
G01X783903Y436013D02*
X783466Y436304D01*
Y436888D01*
X783903Y437179D01*
X784340Y436888D01*
Y436304D01*
X783903Y436013D01*
G01X801403Y454096D02*
X799656Y453513D01*
X798346Y452054D01*
X797473Y450305D01*
X796818Y447971D01*
X796600Y445346D01*
X796818Y442721D01*
X797473Y440387D01*
X798346Y438637D01*
X799656Y437179D01*
X801403Y436596D01*
X803149Y437179D01*
X804460Y438637D01*
X805333Y440387D01*
X805988Y442721D01*
X806206Y445346D01*
X805988Y447971D01*
X805333Y450305D01*
X804460Y452054D01*
X803149Y453513D01*
X801403Y454096D01*
G01X689400Y540546D02*
Y558046D01*
X693766D01*
X695513Y557171D01*
X696823Y556004D01*
X697915Y554255D01*
X698788Y552212D01*
X699006Y549296D01*
X698788Y546379D01*
X697915Y544337D01*
X696823Y542587D01*
X695513Y541421D01*
X693766Y540546D01*
X689400D01*
G01X707336D02*
Y558046D01*
X712576D01*
X714323Y557171D01*
X715633Y555129D01*
X716070Y552796D01*
X715633Y550463D01*
X714541Y548713D01*
X712576Y547837D01*
X707336D01*
G01X744083Y558046D02*
X749323D01*
G01X746703D02*
Y540546D01*
G01X744083D02*
X749323D01*
G01X758526D02*
Y558046D01*
X764203Y543463D01*
X769880Y558046D01*
Y540546D01*
G01X777336D02*
Y558046D01*
X782576D01*
X784323Y557171D01*
X785633Y555129D01*
X786070Y552796D01*
X785633Y550463D01*
X784541Y548713D01*
X782576Y547837D01*
X777336D01*
G01X803570Y540546D02*
X794836D01*
Y558046D01*
X803570D01*
G01X800076Y549588D02*
X794836D01*
G01X811900Y540546D02*
Y558046D01*
X816266D01*
X818013Y557171D01*
X819323Y556004D01*
X820415Y554255D01*
X821288Y552212D01*
X821506Y549296D01*
X821288Y546379D01*
X820415Y544337D01*
X819323Y542587D01*
X818013Y541421D01*
X816266Y540546D01*
X811900D01*
G01X828744D02*
X834203Y558046D01*
X839662Y540546D01*
G01X837696Y546671D02*
X830709D01*
G01X846681Y540546D02*
Y558046D01*
X856725Y540546D01*
Y558046D01*
G01X874006Y556587D02*
X872696Y557463D01*
X871168Y558046D01*
X869421D01*
X867456Y557171D01*
X865928Y555713D01*
X864836Y553962D01*
X863963Y551046D01*
X863744Y548421D01*
X864181Y545796D01*
X864836Y544046D01*
X866146Y542296D01*
X867675Y541129D01*
X869203Y540546D01*
X870731D01*
X872260Y541129D01*
X873570Y542004D01*
X874662Y543170D01*
G01X891070Y540546D02*
X882336D01*
Y558046D01*
X891070D01*
G01X887576Y549588D02*
X882336D01*
G01X921703Y558046D02*
Y540546D01*
G01X916681Y558046D02*
X926725D01*
G01X933744Y540546D02*
X939203Y558046D01*
X944662Y540546D01*
G01X942696Y546671D02*
X935709D01*
G01X958449Y549879D02*
X959323Y550754D01*
X959978Y552212D01*
X960415Y554255D01*
X959978Y556004D01*
X959105Y557171D01*
X957576Y558046D01*
X951681D01*
Y540546D01*
X958886D01*
X960415Y541712D01*
X961288Y543463D01*
X961725Y545504D01*
X961288Y547546D01*
X959978Y549296D01*
X958449Y549879D01*
X951681D01*
G01X969836Y558046D02*
Y540546D01*
X978570D01*
G01X996070D02*
X987336D01*
Y558046D01*
X996070D01*
G01X992576Y549588D02*
X987336D01*
G01X1009203Y539963D02*
X1008766Y540254D01*
Y540838D01*
X1009203Y541129D01*
X1009640Y540838D01*
Y540254D01*
X1009203Y539963D01*
G01Y547837D02*
X1008766Y548129D01*
Y548713D01*
X1009203Y549004D01*
X1009640Y548713D01*
Y548129D01*
X1009203Y547837D01*
G01X1039836Y558046D02*
Y540546D01*
X1048570D01*
G01X1061703D02*
Y558046D01*
X1059083Y554546D01*
G01Y540546D02*
X1064323D01*
G01X711283Y523396D02*
X716523D01*
G01X713903D02*
Y505896D01*
G01X711283D02*
X716523D01*
G01X725726D02*
Y523396D01*
X731403Y508813D01*
X737080Y523396D01*
Y505896D01*
G01X744536D02*
Y523396D01*
X749776D01*
X751523Y522521D01*
X752833Y520479D01*
X753270Y518146D01*
X752833Y515813D01*
X751741Y514063D01*
X749776Y513187D01*
X744536D01*
G01X765311Y500063D02*
X763128Y502979D01*
X762036Y505896D01*
Y517562D01*
X763128Y520479D01*
X765311Y523396D01*
G01X783903Y505896D02*
X782156Y506188D01*
X780628Y507354D01*
X779318Y509104D01*
X778444Y511146D01*
X778008Y513479D01*
Y515813D01*
X778444Y518146D01*
X779318Y520188D01*
X780628Y521937D01*
X782156Y523104D01*
X783903Y523396D01*
X785649Y523104D01*
X787178Y521937D01*
X788488Y520188D01*
X789362Y518146D01*
X789798Y515813D01*
Y513479D01*
X789362Y511146D01*
X788488Y509104D01*
X787178Y507354D01*
X785649Y506188D01*
X783903Y505896D01*
G01X797691D02*
Y523396D01*
G01Y514938D02*
X798783Y516396D01*
X799875Y517271D01*
X801621Y517562D01*
X802931Y517271D01*
X804460Y516104D01*
X805115Y514354D01*
Y505896D01*
G01X812353D02*
Y517562D01*
G01Y514354D02*
X813008Y515813D01*
X814100Y516979D01*
X815628Y517562D01*
X817156Y516979D01*
X818248Y515813D01*
X818903Y514354D01*
Y505896D01*
G01Y514354D02*
X819558Y515813D01*
X820649Y516979D01*
X822178Y517562D01*
X823706Y516979D01*
X824798Y515813D01*
X825453Y514063D01*
Y505896D01*
G01X837495Y500063D02*
X839678Y502979D01*
X840770Y505896D01*
Y517562D01*
X839678Y520479D01*
X837495Y523396D01*
G01X891103D02*
X894159Y505896D01*
X897653Y523396D01*
X901146Y505896D01*
X904203Y523396D01*
G01X912533D02*
X917773D01*
G01X915153D02*
Y505896D01*
G01X912533D02*
X917773D01*
G01X927850D02*
Y523396D01*
X932216D01*
X933963Y522521D01*
X935273Y521354D01*
X936365Y519605D01*
X937238Y517562D01*
X937456Y514646D01*
X937238Y511729D01*
X936365Y509687D01*
X935273Y507937D01*
X933963Y506771D01*
X932216Y505896D01*
X927850D01*
G01X950153Y523396D02*
Y505896D01*
G01X945131Y523396D02*
X955175D01*
G01X963068Y505896D02*
Y523396D01*
G01X972238D02*
Y505896D01*
G01Y514646D02*
X963068D01*
G01X984061Y500063D02*
X981878Y502979D01*
X980786Y505896D01*
Y517562D01*
X981878Y520479D01*
X984061Y523396D01*
G01X996103Y505896D02*
Y517562D01*
G01Y514354D02*
X996758Y515813D01*
X997850Y516979D01*
X999378Y517562D01*
X1000906Y516979D01*
X1001998Y515813D01*
X1002653Y514354D01*
Y505896D01*
G01Y514354D02*
X1003308Y515813D01*
X1004399Y516979D01*
X1005928Y517562D01*
X1007456Y516979D01*
X1008548Y515813D01*
X1009203Y514063D01*
Y505896D01*
G01X1020153Y517562D02*
Y505896D01*
G01Y522229D02*
X1019716Y522521D01*
Y523104D01*
X1020153Y523396D01*
X1020590Y523104D01*
Y522521D01*
X1020153Y522229D01*
G01X1037653Y505896D02*
Y523396D01*
G01X1051878Y507937D02*
X1052970Y506771D01*
X1054498Y505896D01*
X1055808D01*
X1057118Y506479D01*
X1057991Y507354D01*
X1058428Y508520D01*
X1058210Y510271D01*
X1057336Y511146D01*
X1053406Y512896D01*
X1052533Y514938D01*
X1052970Y516396D01*
X1053843Y517271D01*
X1055153Y517562D01*
X1056463Y517271D01*
X1057773Y516396D01*
G01X1073745Y500063D02*
X1075928Y502979D01*
X1077020Y505896D01*
Y517562D01*
X1075928Y520479D01*
X1073745Y523396D01*
G01X927850Y473870D02*
X929159Y472412D01*
X930688Y471538D01*
X932653Y471246D01*
X934618Y471829D01*
X936146Y472996D01*
X937238Y475037D01*
X937456Y477371D01*
X937020Y479704D01*
X935928Y481163D01*
X934399Y482329D01*
X932871Y482621D01*
X931343Y482329D01*
X929378Y481163D01*
X930033Y488746D01*
X935928D01*
G01X950153Y470663D02*
X949716Y470954D01*
Y471538D01*
X950153Y471829D01*
X950590Y471538D01*
Y470954D01*
X950153Y470663D01*
G01X967653Y488746D02*
X965906Y488163D01*
X964596Y486704D01*
X963723Y484955D01*
X963068Y482621D01*
X962850Y479996D01*
X963068Y477371D01*
X963723Y475037D01*
X964596Y473287D01*
X965906Y471829D01*
X967653Y471246D01*
X969399Y471829D01*
X970710Y473287D01*
X971583Y475037D01*
X972238Y477371D01*
X972456Y479996D01*
X972238Y482621D01*
X971583Y484955D01*
X970710Y486704D01*
X969399Y488163D01*
X967653Y488746D01*
G01X981223Y470663D02*
X989083Y488746D01*
G01X1002216Y471246D02*
X1002653Y475037D01*
X1003308Y478246D01*
X1004181Y481163D01*
X1005273Y484371D01*
X1007020Y488746D01*
X998286D01*
G01X1020153Y470663D02*
X1019716Y470954D01*
Y471538D01*
X1020153Y471829D01*
X1020590Y471538D01*
Y470954D01*
X1020153Y470663D01*
G01X1037653Y488746D02*
X1035906Y488163D01*
X1034596Y486704D01*
X1033723Y484955D01*
X1033068Y482621D01*
X1032850Y479996D01*
X1033068Y477371D01*
X1033723Y475037D01*
X1034596Y473287D01*
X1035906Y471829D01*
X1037653Y471246D01*
X1039399Y471829D01*
X1040710Y473287D01*
X1041583Y475037D01*
X1042238Y477371D01*
X1042456Y479996D01*
X1042238Y482621D01*
X1041583Y484955D01*
X1040710Y486704D01*
X1039399Y488163D01*
X1037653Y488746D01*
G01X935273Y436596D02*
Y454096D01*
X927194Y441554D01*
X938112D01*
G01X950153Y436013D02*
X949716Y436304D01*
Y436888D01*
X950153Y437179D01*
X950590Y436888D01*
Y436304D01*
X950153Y436013D01*
G01X962850Y439220D02*
X964159Y437762D01*
X965688Y436888D01*
X967653Y436596D01*
X969618Y437179D01*
X971146Y438346D01*
X972238Y440387D01*
X972456Y442721D01*
X972020Y445054D01*
X970928Y446513D01*
X969399Y447679D01*
X967871Y447971D01*
X966343Y447679D01*
X964378Y446513D01*
X965033Y454096D01*
X970928D01*
G01X981223Y436013D02*
X989083Y454096D01*
G01X1002216Y436596D02*
X1002653Y440387D01*
X1003308Y443596D01*
X1004181Y446513D01*
X1005273Y449721D01*
X1007020Y454096D01*
X998286D01*
G01X1020153Y436013D02*
X1019716Y436304D01*
Y436888D01*
X1020153Y437179D01*
X1020590Y436888D01*
Y436304D01*
X1020153Y436013D01*
G01X1037653Y454096D02*
X1035906Y453513D01*
X1034596Y452054D01*
X1033723Y450305D01*
X1033068Y447971D01*
X1032850Y445346D01*
X1033068Y442721D01*
X1033723Y440387D01*
X1034596Y438637D01*
X1035906Y437179D01*
X1037653Y436596D01*
X1039399Y437179D01*
X1040710Y438637D01*
X1041583Y440387D01*
X1042238Y442721D01*
X1042456Y445346D01*
X1042238Y447971D01*
X1041583Y450305D01*
X1040710Y452054D01*
X1039399Y453513D01*
X1037653Y454096D01*
G01X1146600Y471246D02*
Y488746D01*
X1150966D01*
X1152713Y487871D01*
X1154023Y486704D01*
X1155115Y484955D01*
X1155988Y482912D01*
X1156206Y479996D01*
X1155988Y477079D01*
X1155115Y475037D01*
X1154023Y473287D01*
X1152713Y472121D01*
X1150966Y471246D01*
X1146600D01*
G01X1164536D02*
Y488746D01*
X1169776D01*
X1171523Y487871D01*
X1172833Y485829D01*
X1173270Y483496D01*
X1172833Y481163D01*
X1171741Y479413D01*
X1169776Y478537D01*
X1164536D01*
G01X1146600Y436596D02*
Y454096D01*
X1150966D01*
X1152713Y453221D01*
X1154023Y452054D01*
X1155115Y450305D01*
X1155988Y448262D01*
X1156206Y445346D01*
X1155988Y442429D01*
X1155115Y440387D01*
X1154023Y438637D01*
X1152713Y437471D01*
X1150966Y436596D01*
X1146600D01*
G01X1164536D02*
Y454096D01*
X1169776D01*
X1171523Y453221D01*
X1172833Y451179D01*
X1173270Y448846D01*
X1172833Y446513D01*
X1171741Y444763D01*
X1169776Y443887D01*
X1164536D01*
G01X1133903Y523396D02*
Y505896D01*
G01X1128881Y523396D02*
X1138925D01*
G01X1151403Y505896D02*
Y513771D01*
X1147036Y523396D01*
G01X1155770D02*
X1151403Y513771D01*
G01X1164536Y505896D02*
Y523396D01*
X1169776D01*
X1171523Y522521D01*
X1172833Y520479D01*
X1173270Y518146D01*
X1172833Y515813D01*
X1171741Y514063D01*
X1169776Y513187D01*
X1164536D01*
G01X1190770Y505896D02*
X1182036D01*
Y523396D01*
X1190770D01*
G01X1187276Y514938D02*
X1182036D01*
G01X1339203Y482912D02*
Y471246D01*
G01Y487579D02*
X1338766Y487871D01*
Y488454D01*
X1339203Y488746D01*
X1339640Y488454D01*
Y487871D01*
X1339203Y487579D01*
G01X1353428Y473287D02*
X1354520Y472121D01*
X1356048Y471246D01*
X1357358D01*
X1358668Y471829D01*
X1359541Y472704D01*
X1359978Y473870D01*
X1359760Y475621D01*
X1358886Y476496D01*
X1354956Y478246D01*
X1354083Y480288D01*
X1354520Y481746D01*
X1355393Y482621D01*
X1356703Y482912D01*
X1358013Y482621D01*
X1359323Y481746D01*
G01X1386681Y471246D02*
Y488746D01*
X1396725Y471246D01*
Y488746D01*
G01X1409203Y471246D02*
X1407456Y471538D01*
X1405928Y472704D01*
X1404618Y474454D01*
X1403744Y476496D01*
X1403308Y478829D01*
Y481163D01*
X1403744Y483496D01*
X1404618Y485538D01*
X1405928Y487287D01*
X1407456Y488454D01*
X1409203Y488746D01*
X1410949Y488454D01*
X1412478Y487287D01*
X1413788Y485538D01*
X1414662Y483496D01*
X1415098Y481163D01*
Y478829D01*
X1414662Y476496D01*
X1413788Y474454D01*
X1412478Y472704D01*
X1410949Y471538D01*
X1409203Y471246D01*
G01X1426703Y488746D02*
Y471246D01*
G01X1421681Y488746D02*
X1431725D01*
G01X1457991Y482912D02*
Y474746D01*
X1458865Y472704D01*
X1460175Y471538D01*
X1461703Y471246D01*
X1463231Y471538D01*
X1464541Y472704D01*
X1465415Y474746D01*
G01Y471246D02*
Y482912D01*
G01X1475928Y473287D02*
X1477020Y472121D01*
X1478548Y471246D01*
X1479858D01*
X1481168Y471829D01*
X1482041Y472704D01*
X1482478Y473870D01*
X1482260Y475621D01*
X1481386Y476496D01*
X1477456Y478246D01*
X1476583Y480288D01*
X1477020Y481746D01*
X1477893Y482621D01*
X1479203Y482912D01*
X1480513Y482621D01*
X1481823Y481746D01*
G01X1493428Y479121D02*
X1500415D01*
X1499760Y481163D01*
X1498668Y482329D01*
X1497140Y482912D01*
X1495611Y482621D01*
X1494301Y481746D01*
X1493428Y479704D01*
X1492991Y477954D01*
Y476204D01*
X1493428Y474454D01*
X1494520Y472704D01*
X1495830Y471538D01*
X1497358Y471246D01*
X1498886Y471829D01*
X1500415Y473579D01*
G01X1518133Y488746D02*
Y471246D01*
G01Y473870D02*
X1517260Y472412D01*
X1515949Y471538D01*
X1514421Y471246D01*
X1512675Y471829D01*
X1511365Y473287D01*
X1510491Y475037D01*
X1510273Y477079D01*
X1510491Y479121D01*
X1511365Y480871D01*
X1512675Y482329D01*
X1514421Y482912D01*
X1515949Y482621D01*
X1517041Y482037D01*
X1518133Y480871D01*
G01X1264400Y505313D02*
X1274006Y518146D01*
G01X1269203Y520479D02*
Y502979D01*
G01X1274006Y505313D02*
X1264400Y518146D01*
G01X1262653Y511729D02*
X1275753D01*
G01X1301365D02*
X1307041D01*
G01X1334400Y505896D02*
Y523396D01*
X1338766D01*
X1340513Y522521D01*
X1341823Y521354D01*
X1342915Y519605D01*
X1343788Y517562D01*
X1344006Y514646D01*
X1343788Y511729D01*
X1342915Y509687D01*
X1341823Y507937D01*
X1340513Y506771D01*
X1338766Y505896D01*
X1334400D01*
G01X1353428Y513771D02*
X1360415D01*
X1359760Y515813D01*
X1358668Y516979D01*
X1357140Y517562D01*
X1355611Y517271D01*
X1354301Y516396D01*
X1353428Y514354D01*
X1352991Y512604D01*
Y510854D01*
X1353428Y509104D01*
X1354520Y507354D01*
X1355830Y506188D01*
X1357358Y505896D01*
X1358886Y506479D01*
X1360415Y508229D01*
G01X1370491Y505896D02*
Y517562D01*
G01Y514646D02*
X1371365Y516104D01*
X1372675Y517271D01*
X1374421Y517562D01*
X1375949Y517271D01*
X1377260Y516104D01*
X1377915Y514063D01*
Y505896D01*
G01X1391703D02*
X1390393Y506188D01*
X1389083Y507354D01*
X1388209Y509396D01*
X1387773Y511729D01*
X1388209Y514063D01*
X1389083Y516104D01*
X1390393Y517271D01*
X1391703Y517562D01*
X1393013Y517271D01*
X1394323Y516104D01*
X1395196Y514063D01*
X1395415Y511729D01*
X1395196Y509396D01*
X1394323Y507354D01*
X1393013Y506188D01*
X1391703Y505896D01*
G01X1409203Y523396D02*
Y505896D01*
G01X1406146Y517562D02*
X1412260D01*
G01X1423428Y513771D02*
X1430415D01*
X1429760Y515813D01*
X1428668Y516979D01*
X1427140Y517562D01*
X1425611Y517271D01*
X1424301Y516396D01*
X1423428Y514354D01*
X1422991Y512604D01*
Y510854D01*
X1423428Y509104D01*
X1424520Y507354D01*
X1425830Y506188D01*
X1427358Y505896D01*
X1428886Y506479D01*
X1430415Y508229D01*
G01X1440928Y507937D02*
X1442020Y506771D01*
X1443548Y505896D01*
X1444858D01*
X1446168Y506479D01*
X1447041Y507354D01*
X1447478Y508520D01*
X1447260Y510271D01*
X1446386Y511146D01*
X1442456Y512896D01*
X1441583Y514938D01*
X1442020Y516396D01*
X1442893Y517271D01*
X1444203Y517562D01*
X1445513Y517271D01*
X1446823Y516396D01*
G01X1479203Y523396D02*
Y505896D01*
G01X1476146Y517562D02*
X1482260D01*
G01X1492991Y505896D02*
Y523396D01*
G01Y514938D02*
X1494083Y516396D01*
X1495175Y517271D01*
X1496921Y517562D01*
X1498231Y517271D01*
X1499760Y516104D01*
X1500415Y514354D01*
Y505896D01*
G01X1518133D02*
Y517562D01*
G01Y515521D02*
X1517260Y516687D01*
X1515949Y517271D01*
X1514421Y517562D01*
X1512893Y516979D01*
X1511583Y515813D01*
X1510709Y514063D01*
X1510273Y511729D01*
X1510709Y509396D01*
X1511583Y507646D01*
X1512893Y506479D01*
X1514421Y505896D01*
X1515949Y506188D01*
X1517260Y507062D01*
X1518133Y508229D01*
G01X1531703Y523396D02*
Y505896D01*
G01X1528646Y517562D02*
X1534760D01*
G01X1566703Y523396D02*
Y505896D01*
G01X1563646Y517562D02*
X1569760D01*
G01X1580491Y505896D02*
Y523396D01*
G01Y514938D02*
X1581583Y516396D01*
X1582675Y517271D01*
X1584421Y517562D01*
X1585731Y517271D01*
X1587260Y516104D01*
X1587915Y514354D01*
Y505896D01*
G01X1601703Y517562D02*
Y505896D01*
G01Y522229D02*
X1601266Y522521D01*
Y523104D01*
X1601703Y523396D01*
X1602140Y523104D01*
Y522521D01*
X1601703Y522229D01*
G01X1615928Y507937D02*
X1617020Y506771D01*
X1618548Y505896D01*
X1619858D01*
X1621168Y506479D01*
X1622041Y507354D01*
X1622478Y508520D01*
X1622260Y510271D01*
X1621386Y511146D01*
X1617456Y512896D01*
X1616583Y514938D01*
X1617020Y516396D01*
X1617893Y517271D01*
X1619203Y517562D01*
X1620513Y517271D01*
X1621823Y516396D01*
G01X1651583Y523396D02*
X1656823D01*
G01X1654203D02*
Y505896D01*
G01X1651583D02*
X1656823D01*
G01X1665153D02*
Y517562D01*
G01Y514354D02*
X1665808Y515813D01*
X1666900Y516979D01*
X1668428Y517562D01*
X1669956Y516979D01*
X1671048Y515813D01*
X1671703Y514354D01*
Y505896D01*
G01Y514354D02*
X1672358Y515813D01*
X1673449Y516979D01*
X1674978Y517562D01*
X1676506Y516979D01*
X1677598Y515813D01*
X1678253Y514063D01*
Y505896D01*
G01X1685273Y500063D02*
Y517562D01*
G01Y514938D02*
X1686365Y516396D01*
X1687456Y517271D01*
X1689203Y517562D01*
X1690731Y517271D01*
X1692260Y515813D01*
X1692915Y513771D01*
X1693133Y511729D01*
X1692915Y509687D01*
X1692260Y507646D01*
X1690949Y506479D01*
X1689203Y505896D01*
X1687675Y506188D01*
X1686146Y507062D01*
X1685273Y508229D01*
G01X1703428Y513771D02*
X1710415D01*
X1709760Y515813D01*
X1708668Y516979D01*
X1707140Y517562D01*
X1705611Y517271D01*
X1704301Y516396D01*
X1703428Y514354D01*
X1702991Y512604D01*
Y510854D01*
X1703428Y509104D01*
X1704520Y507354D01*
X1705830Y506188D01*
X1707358Y505896D01*
X1708886Y506479D01*
X1710415Y508229D01*
G01X1728133Y523396D02*
Y505896D01*
G01Y508520D02*
X1727260Y507062D01*
X1725949Y506188D01*
X1724421Y505896D01*
X1722675Y506479D01*
X1721365Y507937D01*
X1720491Y509687D01*
X1720273Y511729D01*
X1720491Y513771D01*
X1721365Y515521D01*
X1722675Y516979D01*
X1724421Y517562D01*
X1725949Y517271D01*
X1727041Y516687D01*
X1728133Y515521D01*
G01X1745633Y505896D02*
Y517562D01*
G01Y515521D02*
X1744760Y516687D01*
X1743449Y517271D01*
X1741921Y517562D01*
X1740393Y516979D01*
X1739083Y515813D01*
X1738209Y514063D01*
X1737773Y511729D01*
X1738209Y509396D01*
X1739083Y507646D01*
X1740393Y506479D01*
X1741921Y505896D01*
X1743449Y506188D01*
X1744760Y507062D01*
X1745633Y508229D01*
G01X1755491Y505896D02*
Y517562D01*
G01Y514646D02*
X1756365Y516104D01*
X1757675Y517271D01*
X1759421Y517562D01*
X1760949Y517271D01*
X1762260Y516104D01*
X1762915Y514063D01*
Y505896D01*
G01X1780196Y516104D02*
X1778668Y517271D01*
X1777358Y517562D01*
X1775611Y516979D01*
X1774301Y515813D01*
X1773428Y513771D01*
X1773209Y511729D01*
X1773428Y509687D01*
X1774301Y507937D01*
X1775611Y506479D01*
X1777358Y505896D01*
X1778886Y506479D01*
X1780196Y507646D01*
G01X1790928Y513771D02*
X1797915D01*
X1797260Y515813D01*
X1796168Y516979D01*
X1794640Y517562D01*
X1793111Y517271D01*
X1791801Y516396D01*
X1790928Y514354D01*
X1790491Y512604D01*
Y510854D01*
X1790928Y509104D01*
X1792020Y507354D01*
X1793330Y506188D01*
X1794858Y505896D01*
X1796386Y506479D01*
X1797915Y508229D01*
G54D13*
G01X423959Y78623D02*
Y79305D01*
G01X425109Y78145D02*
Y79067D01*
G01X422616Y77280D02*
X423959Y78623D01*
G01X422729Y75765D02*
X425109Y78145D01*
G01X421579Y76242D02*
X422616Y77279D01*
G01X422729Y75765D02*
X425109Y78145D01*
G01X421579Y73842D02*
Y76242D01*
G01X422729Y74319D02*
Y75765D01*
G01X422691Y72730D02*
X421579Y73842D01*
G01X423841Y73207D02*
X422729Y74319D01*
G01X422691Y71038D02*
Y72730D01*
G01X423841Y71094D02*
Y73207D01*
G01X425109Y78145D02*
Y79067D01*
G01X423959Y78623D02*
Y79305D01*
G01X422729Y75765D02*
X425109Y78145D01*
G01X422616Y77280D02*
X423959Y78623D01*
G01X421579Y76242D02*
X422616Y77279D01*
G01X422729Y74319D02*
Y75765D01*
G01X421579Y73842D02*
Y76242D01*
G01X423841Y73207D02*
X422729Y74319D01*
G01X422691Y72730D02*
X421579Y73842D01*
G01X423841Y71094D02*
Y73207D01*
G01X422691Y71038D02*
Y72730D01*
G01X460378Y51132D02*
X455250D01*
G01X455369Y49982D02*
X460289D01*
G01X455369D02*
X460289D01*
G01X460378Y51132D02*
X455250D01*
G01X460378D02*
X455250D01*
G01X455369Y49982D02*
X460289D01*
G01X455369D02*
X460289D01*
G01X460378Y51132D02*
X455250D01*
G01X428597Y73542D02*
Y70904D01*
G01X429747Y73065D02*
Y70904D01*
G01X445455Y90400D02*
X428597Y73542D01*
G01X445932Y89250D02*
X429747Y73065D01*
G01X450062Y90400D02*
X445455D01*
G01X450341Y89250D02*
X445932D01*
G01X432534Y72361D02*
Y70733D01*
G01X433684Y71884D02*
Y70818D01*
G01X443157Y82984D02*
X432534Y72361D01*
G01X443634Y81834D02*
X433684Y71884D01*
G01X453469Y82984D02*
X443157D01*
G01X453946Y81834D02*
X443634D01*
G01X454950Y84465D02*
X453469Y82984D01*
G01X456100Y83988D02*
X453946Y81834D01*
G01X454950Y103937D02*
Y84465D01*
G01X456100Y104006D02*
Y83988D01*
G01X429747Y73065D02*
Y70904D01*
G01X428597Y73542D02*
Y70904D01*
G01X445932Y89250D02*
X429747Y73065D01*
G01X445455Y90400D02*
X428597Y73542D01*
G01X450341Y89250D02*
X445932D01*
G01X450062Y90400D02*
X445455D01*
G01X433684Y71884D02*
Y70818D01*
G01X432534Y72361D02*
Y70733D01*
G01X443634Y81834D02*
X433684Y71884D01*
G01X443157Y82984D02*
X432534Y72361D01*
G01X453946Y81834D02*
X443634D01*
G01X453469Y82984D02*
X443157D01*
G01X456100Y83988D02*
X453946Y81834D01*
G01X454950Y84465D02*
X453469Y82984D01*
G01X456100Y104006D02*
Y83988D01*
G01X454950Y103937D02*
Y84465D01*
G01X445458Y51069D02*
X448875D01*
G01X444981Y49919D02*
X448906D01*
G01X442845Y53682D02*
X445458Y51069D01*
G01X442368Y52532D02*
X444981Y49919D01*
G01X441063Y52532D02*
X442368D01*
G01X441063Y53682D02*
X442845D01*
G01X441063Y52532D02*
X442368D01*
G01X444981Y49919D02*
X448906D01*
G01X445458Y51069D02*
X448875D01*
G01X442368Y52532D02*
X444981Y49919D01*
G01X442845Y53682D02*
X445458Y51069D01*
G01X441063Y52532D02*
X442368D01*
G01X442845Y53682D02*
X445458Y51069D01*
G01X441063Y53682D02*
X442845D01*
G01X528929Y-39863D02*
X528679Y-38786D01*
G01X527557Y-39046D02*
X527419Y-38450D01*
G01X528383Y-42594D02*
X527557Y-39046D01*
G01X529448Y-42095D02*
X528929Y-39863D01*
G01X528383Y-42594D02*
X527557Y-39046D01*
G01X530379Y-43326D02*
X529448Y-42095D01*
G01X533893Y-49883D02*
X528383Y-42594D01*
G01X535043Y-49497D02*
X530379Y-43326D01*
G01X533893Y-49883D02*
X528383Y-42594D01*
G01X535043Y-57615D02*
Y-49497D01*
G01X533893Y-57615D02*
Y-49883D01*
G01X527557Y-39046D02*
X527419Y-38450D01*
G01X528929Y-39863D02*
X528679Y-38786D01*
G01X528383Y-42594D02*
X527557Y-39046D01*
G01X528929Y-39863D02*
X528679Y-38786D01*
G01X529448Y-42095D02*
X528929Y-39863D01*
G01X533893Y-49883D02*
X528383Y-42594D01*
G01X530379Y-43326D02*
X529448Y-42095D01*
G01X535043Y-49497D02*
X530379Y-43326D01*
G01X533893Y-57615D02*
Y-49883D01*
G01X535043Y-57615D02*
Y-49497D01*
G01X528929Y-39863D02*
X528679Y-38786D01*
G01X527557Y-39046D02*
X527419Y-38450D01*
G01X528383Y-42594D02*
X527557Y-39046D01*
G01X529448Y-42095D02*
X528929Y-39863D01*
G01X528383Y-42594D02*
X527557Y-39046D01*
G01X530379Y-43326D02*
X529448Y-42095D01*
G01X533893Y-49883D02*
X528383Y-42594D01*
G01X535043Y-49497D02*
X530379Y-43326D01*
G01X533893Y-49883D02*
X528383Y-42594D01*
G01X535043Y-57615D02*
Y-49497D01*
G01X533893Y-57615D02*
Y-49883D01*
G01X527557Y-39046D02*
X527419Y-38450D01*
G01X528929Y-39863D02*
X528679Y-38786D01*
G01X528383Y-42594D02*
X527557Y-39046D01*
G01X528929Y-39863D02*
X528679Y-38786D01*
G01X529448Y-42095D02*
X528929Y-39863D01*
G01X533893Y-49883D02*
X528383Y-42594D01*
G01X530379Y-43326D02*
X529448Y-42095D01*
G01X535043Y-49497D02*
X530379Y-43326D01*
G01X533893Y-57615D02*
Y-49883D01*
G01X535043Y-57615D02*
Y-49497D01*
M02*
